# Barreleye-G2_Tri-mode BPX24-DVT-X01-SKU-BOM-X07-20171222_Final.xls.xlsx — Changelist (bom)
| BOM Change List Date:Sat May 27 11:46:00 GMT+08:00 2017 |  |  |  |  |  |  |  |  |  |
| New BOM file : C:\<user>\Barreleye_G2-Tri-mode BPX24-EVT-X00-BOM-X01_20170509.xls |  |  |  |  |  |  |  |  |  |
| Old BOM file : C:\<user>\Barreleye_G2-TRI-MODE BPX24-EVT-X00-BOM-X00-20170420.xls |  |  |  |  |  |  |  |  |  |
| ##### Add Parts |  |  |  |  |  |  |  |  |  |
| Item | Location | Qty | Foxconn P/N | Part Description | Manufacturer Full Name | Manufacturer P/N | RoHS | Sheet |  |
| 1 | C15,C19,C216,C217,C224,C2101,C2102,C2103,C2104,C2105,C2106,C2107,C2108,C2109,C2110,C2111,C2112,C2113,C2114,C2115,C2116,C2117,C2118,C2119,C2120,C2121,C2122,C2123,C2124,C2125,C2126,C2127,C2128,C2129,C2130,C2131,C2132,C2133,C2134,C2135,C2136,C2137,C2138,C2139,C2140,C2141,C2142,C2143,C2144,C2145,C2146,C2147,C2148,C2149,C2169,C2171,C2176,C2177,C2178,C2179,C2180,C2181,C2182,C2183,C2184,C2185,C2186,C2187,C2188,C2189,C2190,C2191,C2192,C2193,C2194,C2195,C2196,C2197,C2232,C2233,C2234,C2235,C2237,C2239,C2240,C2241,C2242,C2254,C2255,C2256,C2259,C2260,C2261,C2262,C2263,C2264,C2265,C2266 | 98 | 620101T02-015-G | CAP,100nF,+/-10%,X7R,16V,G,SMD0402 | MURATA ELEC. NORTH AMERICA | GRM155R71C104K | Y | PWA BOM |  |
|  |  |  | 620101T00-012-G | CAP,100nF,+/-10%,X7R,16V,G,SMD0402 | WALSIN | 0402B104K160CT |  | PWA BOM |  |
|  |  |  | 620101T00-026-G | CAP,100nF,+/-10%,X7R,16V,G,SMD0402 | SAMSUNG SEMICONDUCTOR | CL05B104KO5NNNC |  | PWA BOM |  |
|  |  |  | 620101T00-015-G | CAP,100nF,+/-10%,X7R,16V,G,SMD0402 | MURATA ELEC. NORTH AMERICA | GRM155R71C104KA88D |  | PWA BOM |  |
| 2 | C2236,C2238 | 2 | 620100A00-015-G | CAP,10uF,+/-10%,X5R,16V,G,SMD1206 | MURATA ELEC. NORTH AMERICA | GRM31CR61C106K | N | PWA BOM |  |
|  |  |  | 620100A00-026-G | CAP,10uF,+/-10%,X5R,16V,G,SMD1206 | SAMSUNG SEMICONDUCTOR | CL31A106KOHNNNE | G | PWA BOM |  |
|  |  |  | 620100A03-023-G | CAP,10uF,+/-10%,X5R,16V,G,SMD1206 | TAIYO ELECTRIC IND.CO.LTD | EMK316BJ106KL-T | G | PWA BOM |  |
|  |  |  | 620100A00-012-G | CAP,10uF,+/-10%,X5R,16V,G,SMD1206 | WALSIN TECHNOLOGY CORPORATION | 1206X106K160CT | G | PWA BOM |  |
|  |  |  | 620100A00-011-G | CAP,10uF,+/-10%,X5R,16V,G,SMD1206 | YAGEO CORPORATION COMPONENT | CC1206KKX5R7BB106 | G | PWA BOM |  |
| 3 | C215 | 1 | 620105E00-015-G | CAP,1uF,+/-10%,X7R,10V,G,SMD0603 | MURATA ELEC. NORTH AMERICA | GRM188R71A105K |  | PWA BOM |  |
|  |  |  | 620105E00-012-G | CAP,1uF,+/-10%,X7R,10V,G,SMD0603 | WALSIN TECHNOLOGY CORPORATION | 0603B105K100CT | G | PWA BOM |  |
|  |  |  | 620105E00-011-G | CAP,1uF,+/-10%,X7R,10V,G,SMD0603 | YAGEO CORPORATION COMPONENT | CC0603KRX7R6BB105 | G | PWA BOM |  |
|  |  |  | 620105E00-026-G | CAP,1uF,+/-10%,X7R,10V,G,SMD0603 | SAMSUNG SEMICONDUCTOR | CL10B105KP8NNNC | G | PWA BOM |  |
|  |  |  | 620105E01-023-G | CAP,1uF,+/-10%,X7R,10V,G,SMD0603 | TAIYO ELECTRIC IND.CO.LTD | LMK107B7105KA-T | G | PWA BOM |  |
| 4 | C218,C219,C220,C221,C222,C2243,C2244,C2251,C2252 | 9 | 620103600-015-G | CAP,10nF,+/-10%,X7R,25V,G,SMD0402 | MURATA ELEC. NORTH AMERICA | GRM155R71E103K | N | PWA BOM |  |
|  |  |  | 620103600-012-G | CAP,10nF,+/-10%,X7R,25V,G,SMD0402 | WALSIN TECHNOLOGY CORPORATION | 0402B103K250CT | G | PWA BOM |  |
|  |  |  | 620103600-011-G | CAP,10nF,+/-10%,X7R,25V,G,SMD0402 | YAGEO CORPORATION COMPONENT | CC0402KRX7R8BB103 | G | PWA BOM |  |
|  |  |  | 620103600-026-G | CAP,10nF,+/-10%,X7R,25V,G,SMD0402 | SAMSUNG SEMICONDUCTOR | CL05B103KA5NNNC | G | PWA BOM |  |
|  |  |  | 620103601-023-G | CAP,10nF,+/-10%,X7R,25V,G,SMD0402 | TAIYO ELECTRIC IND.CO.LTD | TMK105B7103KV-F | G | PWA BOM |  |
| 5 | C214 | 1 | 62010L000-015-G | CAP,10uF,+/-20%,X5R,6.3V,G,SMD0603 | MURATA ELEC. NORTH AMERICA | GRM188R60J106M | N | PWA BOM |  |
|  |  |  | 62010L000-023-G | CAP,10uF,+/-20%,X5R,6.3V,G,SMD0603 | TAIYO ELECTRIC IND.CO.LTD | JMK107BJ106MA-T | G | PWA BOM |  |
|  |  |  | 62010L000-012-G | CAP,10uF,+/-20%,X5R,6.3V,G,SMD0603 | WALSIN TECHNOLOGY CORPORATION | 0603X106M6R3CT | G | PWA BOM |  |
|  |  |  | 62010L000-026-G | CAP,10uF,+/-20%,X5R,6.3V,G,SMD0603 | SAMSUNG SEMICONDUCTOR | CL10A106MQ8NNNC | G | PWA BOM |  |
|  |  |  | 62010L000-011-G | CAP,10uF,+/-20%,X5R,6.3V,G,SMD0603 | YAGEO CORPORATION COMPONENT | CC0603MRX5R5BB106 | G | PWA BOM |  |
| 6 | C223 | 1 | 62011NF01-015-G | CAP,2.2uF,+/-10%,X7R,25V,G,SMD0805 | MURATA ELEC. NORTH AMERICA | GRM21BR71E225K |  | PWA BOM |  |
|  |  |  | 62011NF00-026-G | CAP,2.2uF,+/-10%,X7R,25V,G,SMD0805 | SAMSUNG SEMICONDUCTOR | CL21B225KAFNNNE |  | PWA BOM |  |
|  |  |  | 62011NF00-023-G | CAP,2.2uF,+/-10%,X7R,25V,G,SMD0805 | TAIYO ELECTRIC IND.CO.LTD | TMK212B7225KG-TR |  | PWA BOM |  |
| 7 | C1946,C2081,C2253 | 3 | 620114000-015-G | CAP,10uF,+/-10%,X5R,16V,G,SMD0805 | MURATA ELEC. NORTH AMERICA | GRM21BR61C106K | N | PWA BOM |  |
| 8 | C1950,C2080,C2245,C2246,C2247,C2248,C2249,C2250,C2257,C2258 | 10 | 620105400-015-G | CAP,1uF,+/-10%,X7R,16V,G,SMD0603 | MURATA ELEC. NORTH AMERICA | GRM188R71C105K | N | PWA BOM |  |
|  |  |  | 620105400-012-G | CAP,1uF,+/-10%,X7R,16V,G,SMD0603 | WALSIN TECHNOLOGY CORPORATION | 0603B105K160CT | G | PWA BOM |  |
|  |  |  | 620105400-011-G | CAP,1uF,+/-10%,X7R,16V,G,SMD0603 | YAGEO CORPORATION COMPONENT | CC0603KRX7R7BB105 | G | PWA BOM |  |
|  |  |  | 620105400-026-G | CAP,1uF,+/-10%,X7R,16V,G,SMD0603 | SAMSUNG SEMICONDUCTOR | CL10B105KO8NNNC | G | PWA BOM |  |
|  |  |  | 620105400-023-G | CAP,1uF,+/-10%,X7R,16V,G,SMD0603 | TAIYO ELECTRIC IND.CO.LTD | EMK107B7105KA-T | G | PWA BOM |  |
| 9 | C2198,C2208,C2209,C2210,C2211,C2212,C2213,C2214,C2215,C2216,C2217,C2218,C2219,C2220,C2221,C2222,C2223,C2224 | 18 | 62011LU00-015-G | CAP,100nF,+/-10%,X5R,16V,G,SMD0402 | MURATA ELEC. NORTH AMERICA | GRM155R61C104KA88D | Y | PWA BOM |  |
| 10 | C2231 | 1 | 620109S00-015-G | CAP,4.7uF,+/-10%,X7R,10V,G,SMD0805 | MURATA ELEC. NORTH AMERICA | GRM21BR71A475K | N | PWA BOM |  |
|  |  |  | 620109S00-023-G | CAP,4.7uF,+/-10%,X7R,10V,G,SMD0805 | TAIYO ELECTRIC IND.CO.LTD | LMK212B7475KG-T |  | PWA BOM |  |
|  |  |  | 620109S00-026-G | CAP,4.7uF,+/-10%,X7R,10V,G,SMD0805 | SAMSUNG SEMICONDUCTOR | CL21B475KPFNNNE |  | PWA BOM |  |
| 11 | C2267 | 1 | 620106200-015-G | CAP,10nF,+/-10%,X7R,16V,G,SMD0402 | MURATA ELEC. NORTH AMERICA | GRM155R71C103K | N | PWA BOM |  |
|  |  |  | 620106200-012-G | CAP,10nF,+/-10%,X7R,16V,G,SMD0402 | WALSIN | 0402B103K160CT | G | PWA BOM |  |
|  |  |  | 620106200-026-G | CAP,10nF,+/-10%,X7R,16V,G,SMD0402 | SAMSUNG | CL05B103KO5NNNC | G | PWA BOM |  |
|  |  |  | 620106200-023-G | CAP,10nF,+/-10%,X7R,16V,G,SMD0402 | TAIYO | EMK105B7103KV-F | G | PWA BOM |  |
| 12 | C2268,C2269 | 2 | 62012UW00-015-G | CAP,6.8pF,+/-0.05pF,NPO(C0G),25V,G,SMD0402 | MURATA ELEC. NORTH AMERICA | GRM1555C1E6R8WA01D |  | PWA BOM |  |
| 13 | L4 | 1 | 72010JY00-015-G | FB,330 Ohm@100MHz,+/-25%,1.5A,70mOhm,G,SMD0603 | MURATA ELEC. NORTH AMERICA | BLM18SG331TN1D | N | PWA BOM |  |
|  |  |  | 72010JB00-016-G | FB,330 Ohm@100MHz,+/-25%,1.5A,G,80mOhm,SMD0603 | TDK ELECTRONICS EUROPE GMBH | MPZ1608S331AT |  | PWA BOM |  |
| 14 | L6,L28 | 2 | 72010FB01-016-G | FB,600 Ohm@100MHz,+/-25%,1A,150mOhm,G,SMD0603 | TDK ELECTRONICS EUROPE GMBH | MPZ1608S601AT | N | PWA BOM |  |
| 15 | L30 | 1 | 720102001-015-G | FB,30 Ohm@100MHz,+/-25%,3A,15mOhm,G,SMD0805 | MURATA ELEC. NORTH AMERICA | BLM21PG300SN1D | N | PWA BOM |  |
| 16 | L31 | 1 | 720101L00-015-G | FB,600 Ohm@100MHz,+/-25%,200mA,500mOhm,G,SMD0603 | MURATA ELEC. NORTH AMERICA | BLM18AG601SN1D | N | PWA BOM |  |
| 17 | R336,R1605,R1700,R1701,R1702,R1703,R1704,R1705,R1706,R1707,R1708,R1709,R1710,R1711,R1712,R1713,R1714,R1715,R1716,R1717,R1718,R1719,R1720,R1721,R1722,R1723,R1724,R1725,R1726,R1727,R1728,R1729,R1730,R1731,R1732,R1733,R1734,R1735,R1736,R1737,R1738,R1739,R1831,R1832,R1834,R1835,R1837,R1838,R1840,R1841,R1843,R1844,R1846,R1847,R1849,R1850,R1852,R1853,R1855,R1856,R1858,R1859,R1861,R1862,R1864,R1865,R1867,R1868,R1870,R1871,R1873,R1874,R1876,R1877,R1879,R1880,R1882,R1883,R1885,R1886,R2065 | 81 | 61010LA00-017-G | RES,4.7KOhm,+/-1%,1/16W,G,SMD0402 | KOA SPEER ELECTRONICS, INC. | RK73H1ETTP4701F | N | PWA BOM |  |
|  |  |  | 61010LA00-012-G | RES,4.7KOhm,+/-1%,1/16W,G,SMD0402 | WALSIN | WR04X4701FTL |  | PWA BOM |  |
|  |  |  | 61010LA00-011-G | RES,4.7KOhm,+/-1%,1/16W,G,SMD0402 | YAGEO | RC0402FR-074K7L |  | PWA BOM |  |
|  |  |  | 61010LA00-044-G | RES,4.7KOhm,+/-1%,1/16W,G,SMD0402 | TA-I | RM04FTN4701 |  | PWA BOM |  |
| 18 | R60,R65,R568,R569,R570,R571,R1888,R1889,R1890,R1891,R1892,R1893,R1894,R1895,R1896,R1897,R1898,R1899,R1900,R1901,R1902,R1903,R1988,R1989,R1990,R1991,R1992,R1993,R1994,R1995,R1996,R1997,R1998,R1999,R2000,R2001,R2002,R2003,R2004,R2005,R2006,R2007,R2008,R2009,R2010,R2011,R2012,R2013,R2014,R2015,R2016,R2017,R2018,R2019,R2020,R2021,R2022,R2023,R2024,R2025,R2026,R2027,R2028,R2029,R2030,R2031,R2032,R2033,R2034,R2035,R2036,R2037,R2038,R2039,R2040,R2041,R2042,R2043,R2044,R2045,R2046,R2047,R2061,R2066,R2067,R2068,R2069,R2070 | 88 | 610107A00-017-G | RES,0 Ohm,+/-5%,1/16W,G,SMD0402 | KOA SPEER ELECTRONICS, INC. | RK73Z1ETTP | N | PWA BOM |  |
|  |  |  | 610107A00-012-G | RES,0 Ohm,+/-5%,1/16W,G,SMD0402 | WALSIN | WR04X000PTL |  | PWA BOM |  |
|  |  |  | 610107A00-011-G | RES,0 Ohm,+/-5%,1/16W,G,SMD0402 | YAGEO | RC0402JR-070RL |  | PWA BOM |  |
|  |  |  | 610107A00-044-G | RES,0 Ohm,+/-5%,1/16W,G,SMD0402 | TA-I | RM04JTN0 |  | PWA BOM |  |
|  |  |  | 610107A00-024-G | RES,0 Ohm,+/-5%,1/16W,G,SMD0402 | PANASONIC INDUSTRIAL CO.,LTD. | ERJ2GE0R00X |  | PWA BOM |  |
|  |  |  | 610107A00-029-G | RES,0 Ohm,+/-5%,1/16W,G,SMD0402 | VISHAY ENTER TECHNO LOGY.INC | CRCW04020000Z0ED |  | PWA BOM |  |
| 19 | R338,R550,R552,R868,R869,R1833,R1836,R1839,R1842,R1845,R1848,R1851,R1854,R1857,R1860,R1863,R1866,R1869,R1872,R1875,R1878,R1881,R1884,R1887 | 24 | 61011H500-017-G | RES,22 Ohm,+/-1%,1/16W,G,SMD0402 | KOA SPEER ELECTRONICS, INC. | RK73H1ETTP22R0F | N | PWA BOM |  |
|  |  |  | 61011H500-012-G | RES,22 Ohm,+/-1%,1/16W,G,SMD0402 | WALSIN | WR04X22R0FTL |  | PWA BOM |  |
|  |  |  | 61011H500-011-G | RES,22 Ohm,+/-1%,1/16W,G,SMD0402 | YAGEO | RC0402FR-0722RL |  | PWA BOM |  |
|  |  |  | 61011H500-044-G | RES,22 Ohm,+/-1%,1/16W,G,SMD0402 | TA-I | RM04FTN22R0 |  | PWA BOM |  |
|  |  |  | 61011H500-024-G | RES,22 Ohm,+/-1%,1/16W,G,SMD0402 | PANASONIC INDUSTRIAL CO.,LTD. | ERJ2RKF22R0X |  | PWA BOM |  |
| 20 | R50,R51,R52,R53,R62,R96,R97,R546,R547,R548,R549,R553,R555,R556,R557,R559,R560,R866,R1078,R1079,R1569,R1570,R1571,R1572,R1573,R1574,R1575,R1576,R1577,R1578,R1579,R1580,R1581,R1582,R1583,R1584,R1585,R1586,R1587,R1588,R1589,R1590,R1591,R1592,R1593,R1594,R1595,R1596,R1597,R1598,R1599,R1600,R1601,R1602,R1603,R1668,R1681,R1684,R1688,R1694,R1697,R1783 | 62 | 610107B00-017-G | RES,4.7KOhm,+/-5%,1/16W,G,SMD0402 | KOA SPEER ELECTRONICS, INC. | RK73B1ETTP472J | N | PWA BOM |  |
|  |  |  | 610107B00-012-G | RES,4.7KOhm,+/-5%,1/16W,G,SMD0402 | WALSIN | WR04X472JTL |  | PWA BOM |  |
|  |  |  | 610107B00-011-G | RES,4.7KOhm,+/-5%,1/16W,G,SMD0402 | YAGEO | RC0402JR-074K7L |  | PWA BOM |  |
|  |  |  | 610107B00-044-G | RES,4.7KOhm,+/-5%,1/16W,G,SMD0402 | TA-I | RM04JTN472 |  | PWA BOM |  |
|  |  |  | 610107B00-024-G | RES,4.7KOhm,+/-5%,1/16W,G,SMD0402 | PANASONIC INDUSTRIAL CO.,LTD. | ERJ2GEJ472X |  | PWA BOM |  |
|  |  |  | 610107B00-029-G | RES,4.7KOhm,+/-5%,1/16W,G,SMD0402 | VISHAY ENTER TECHNO LOGY.INC | CRCW04024K70JNED |  | PWA BOM |  |
| 21 | R1672,R1673,R1679,R1683,R1687,R1698,R1780,R1782 | 8 | 61010JY00-017-G | RES,220 Ohm,+/-5%,1/16W,G,SMD0402 | KOA SPEER ELECTRONICS, INC. | RK73B1ETTP221J | N | PWA BOM |  |
|  |  |  | 61010JY00-012-G | RES,220 Ohm,+/-5%,1/16W,G,SMD0402 | WALSIN | WR04X221JTL |  | PWA BOM |  |
|  |  |  | 61010JY00-011-G | RES,220 Ohm,+/-5%,1/16W,G,SMD0402 | YAGEO | RC0402JR-07220RL |  | PWA BOM |  |
|  |  |  | 61010JY00-044-G | RES,220 Ohm,+/-5%,1/16W,G,SMD0402 | TA-I | RM04JTN221 |  | PWA BOM |  |
| 22 | R106,R1740,R1741,R1742,R1743,R1744,R1745,R1746,R1747,R1748,R1749,R1750,R1751,R1752,R1753,R1754,R1755,R1756,R1757,R1758,R1759,R1760,R1761,R1762,R1763,R1764,R1765,R1766,R1767,R1768,R1769,R1770,R1771,R1772,R1773,R1774,R1775,R1776,R1777,R1778 | 40 | 610101V00-017-G | RES,22 Ohm,+/-5%,1/16W,G,SMD0402 | KOA SPEER ELECTRONICS, INC. | RK73B1ETTP220J | N | PWA BOM |  |
|  |  |  | 610101V00-012-G | RES,22 Ohm,+/-5%,1/16W,G,SMD0402 | WALSIN | WR04X220JTL |  | PWA BOM |  |
|  |  |  | 610101V00-011-G | RES,22 Ohm,+/-5%,1/16W,G,SMD0402 | YAGEO | RC0402JR-0722RL |  | PWA BOM |  |
|  |  |  | 610101V00-044-G | RES,22 Ohm,+/-5%,1/16W,G,SMD0402 | TA-I | RM04JTN220 |  | PWA BOM |  |
|  |  |  | 610101V00-024-G | RES,22 Ohm,+/-5%,1/16W,G,SMD0402 | PANASONIC INDUSTRIAL CO.,LTD. | ERJ2GEJ220X |  | PWA BOM |  |
| 23 | R315 | 1 | 610115J00-017-G | RES,33 Ohm,+/-1%,1/16W,G,SMD0402 | KOA SPEER ELECTRONICS, INC. | RK73H1ETTP33R0F | N | PWA BOM |  |
|  |  |  | 610115J00-012-G | RES,33 Ohm,+/-1%,1/16W,G,SMD0402 | WALSIN | WR04X33R0FTL |  | PWA BOM |  |
|  |  |  | 610115J00-011-G | RES,33 Ohm,+/-1%,1/16W,G,SMD0402 | YAGEO | RC0402FR-0733RL |  | PWA BOM |  |
|  |  |  | 610115J00-044-G | RES,33 Ohm,+/-1%,1/16W,G,SMD0402 | TA-I | RM04FTN33R0 |  | PWA BOM |  |
|  |  |  | 610115J00-024-G | RES,33 Ohm,+/-1%,1/16W,G,SMD0402 | PANASONIC INDUSTRIAL CO.,LTD. | ERJ2RKF33R0X |  | PWA BOM |  |
| 24 | R348,R1522,R1523,R1524,R1525,R1526,R1527,R1528,R1529,R1530,R1531,R1532,R1533,R1534,R1535,R1536,R1537,R1538,R1539,R1540,R1541,R1542,R1543,R1544,R1545,R1546,R1547,R1548,R1549,R1550,R1551,R1552,R1553,R1554,R1555,R1556,R1557,R1558,R1559,R1560,R1561,R1562,R1563,R1564,R1565,R1566,R1567,R1568 | 48 | 61100LQ00-017-G | RES,20KOhm,+/-1%,1/16W,G,SMD0402 | KOA SPEER ELECTRONICS, INC. | RN731ETTP2002F50 |  | PWA BOM |  |
|  |  |  | 61100LQ00-012-G | RES,20KOhm,+/-1%,1/16W,G,SMD0402 | WALSIN | WF04T2002FTL |  | PWA BOM |  |
|  |  |  | 61100LQ00-011-G | RES,20KOhm,+/-1%,1/16W,G,SMD0402 | YAGEO | RT0402FRE0720KL |  | PWA BOM |  |
|  |  |  | 61100LQ00-044-G | RES,20KOhm,+/-1%,1/16W,G,SMD0402 | TA-I | RB04FTS2002 |  | PWA BOM |  |
| 25 | R544,R545 | 2 | 610114J00-017-G | RES,2KOhm,+/-1%,1/16W,G,SMD0402 | KOA SPEER ELECTRONICS, INC. | RK73H1ETTP2001F | N | PWA BOM |  |
|  |  |  | 610114J00-012-G | RES,2KOhm,+/-1%,1/16W,G,SMD0402 | WALSIN | WR04X2001FTL |  | PWA BOM |  |
|  |  |  | 610114J00-011-G | RES,2KOhm,+/-1%,1/16W,G,SMD0402 | YAGEO | RC0402FR-072KL |  | PWA BOM |  |
|  |  |  | 610114J00-044-G | RES,2KOhm,+/-1%,1/16W,G,SMD0402 | TA-I | RM04FTN2001 |  | PWA BOM |  |
|  |  |  | 610114J00-024-G | RES,2KOhm,+/-1%,1/16W,G,SMD0402 | PANASONIC INDUSTRIAL CO.,LTD. | ERJ2RKF2001X |  | PWA BOM |  |
|  |  |  | 610114J00-029-G | RES,2KOhm,+/-1%,1/16W,G,SMD0402 | VISHAY ENTER TECHNO LOGY.INC | CRCW04022K00FKED |  | PWA BOM |  |
| 26 | R558,R561,R562,R564,R565,R566,R567,R2052,R2082 | 9 | 610100T00-017-G | RES,1KOhm,+/-5%,1/16W,G,SMD0402 | KOA SPEER ELECTRONICS, INC. | RK73B1ETTP102J | N | PWA BOM |  |
|  |  |  | 610100T00-012-G | RES,1KOhm,+/-5%,1/16W,G,SMD0402 | WALSIN | WR04X102JTL |  | PWA BOM |  |
|  |  |  | 610100T00-011-G | RES,1KOhm,+/-5%,1/16W,G,SMD0402 | YAGEO | RC0402JR-071KL |  | PWA BOM |  |
|  |  |  | 610100T00-044-G | RES,1KOhm,+/-5%,1/16W,G,SMD0402 | TA-I | RM04JTN102 |  | PWA BOM |  |
|  |  |  | 610100T00-024-G | RES,1KOhm,+/-5%,1/16W,G,SMD0402 | PANASONIC INDUSTRIAL CO.,LTD. | ERJ2GEJ102X |  | PWA BOM |  |
| 27 | R865,R1072,R1073,R1074,R1077,R1438,R1439,R1440 | 8 | 61010L300-017-G | RES,1KOhm,+/-1%,1/16W,G,SMD0402 | KOA SPEER ELECTRONICS, INC. | RK73H1ETTP1001F | N | PWA BOM |  |
|  |  |  | 61010L300-012-G | RES,1KOhm,+/-1%,1/16W,G,SMD0402 | WALSIN | WR04X1001FTL |  | PWA BOM |  |
|  |  |  | 61010L300-011-G | RES,1KOhm,+/-1%,1/16W,G,SMD0402 | YAGEO | RC0402FR-071KL |  | PWA BOM |  |
|  |  |  | 61010L300-044-G | RES,1KOhm,+/-1%,1/16W,G,SMD0402 | TA-I | RM04FTN1001 |  | PWA BOM |  |
|  |  |  | 61010L300-024-G | RES,1KOhm,+/-1%,1/16W,G,SMD0402 | PANASONIC INDUSTRIAL CO.,LTD. | ERJ2RKF1001X |  | PWA BOM |  |
|  |  |  | 61010L300-029-G | RES,1KOhm,+/-1%,1/16W,G,SMD0402 | VISHAY ENTER TECHNO LOGY.INC | CRCW04021K00FKED |  | PWA BOM |  |
| 28 | R583 | 1 | 61011BQ00-017-G | RES,2.2 Ohm,+/-5%,1/16W,G,SMD0402 | KOA SPEER ELECTRONICS, INC. | RK73B1ETTP2R2J | N | PWA BOM |  |
|  |  |  | 61011BQ00-011-G | RES,2.2 Ohm,+/-5%,1/16W,G,SMD0402 | YAGEO CORPORATION COMPONENT | RC0402JR-072R2L |  | PWA BOM |  |
|  |  |  | 61011BQ00-012-G | RES,2.2 Ohm,+/-5%,1/16W,G,SMD0402 | WALSIN TECHNOLOGY CORPORATION | WR04X2R2JTL |  | PWA BOM |  |
|  |  |  | 61011BQ00-044-G | RES,2.2 Ohm,+/-5%,1/16W,G,SMD0402 | TA-I TECHNOLOGY CO., LTD | RM04JTN2R2 |  | PWA BOM |  |
| 29 | R585 | 1 | 610108300-017-G | RES,0 Ohm,+/-5%,1/10W,G,SMD0603 | KOA SPEER ELECTRONICS, INC. | RK73Z1JTTD | N | PWA BOM |  |
|  |  |  | 610108300-012-G | RES,0 Ohm,+/-5%,1/10W,G,SMD0603 | WALSIN | WR06X000PTL |  | PWA BOM |  |
|  |  |  | 610108300-011-G | RES,0 Ohm,+/-5%,1/10W,G,SMD0603 | YAGEO | RC0603JR-070RL |  | PWA BOM |  |
|  |  |  | 610108300-044-G | RES,0 Ohm,+/-5%,1/10W,G,SMD0603 | TA-I | RM06JTN0 |  | PWA BOM |  |
|  |  |  | 610108300-024-G | RES,0 Ohm,+/-5%,1/10W,G,SMD0603 | PANASONIC INDUSTRIAL CO.,LTD. | ERJ3GEY0R00V |  | PWA BOM |  |
| 30 | R817,R818,R828,R830,R832,R833,R834,R860,R867,R1443,R1444,R1445,R1446,R1447,R1448,R1458,R1459,R1460,R1461,R1462,R1463,R1464,R1465,R1466,R1467,R1468,R1469,R1470,R1471,R1472,R1473,R1604 | 32 | 610118400-017-G | RES,27 Ohm,+/-1%,1/16W,G,SMD0402 | KOA SPEER ELECTRONICS, INC. | RK73H1ETTP27R0F | N | PWA BOM |  |
|  |  |  | 610118400-012-G | RES,27 Ohm,+/-1%,1/16W,G,SMD0402 | WALSIN | WR04X27R0FTL |  | PWA BOM |  |
|  |  |  | 610118400-011-G | RES,27 Ohm,+/-1%,1/16W,G,SMD0402 | YAGEO | RC0402FR-0727RL |  | PWA BOM |  |
|  |  |  | 610118400-044-G | RES,27 Ohm,+/-1%,1/16W,G,SMD0402 | TA-I | RM04FTN27R0 |  | PWA BOM |  |
| 31 | R1785,R1787,R1788,R1791,R1793,R1795,R1796,R1799,R1800,R1803,R1804,R1807,R1808,R1811,R1812,R1815,R1816,R1819,R1820,R1823,R1824,R1827,R1828,R2049,R2050,R2051,R2062,R2063,R2064,R2071,R2075,R2077,R2079,R2083,R2084 | 35 | 61100AH00-017-G | RES,10KOhm,+/-0.5%,1/16W,G,SMD0402 | KOA SPEER ELECTRONICS, INC. | RN731ETTP1002D25 | Y | PWA BOM |  |
|  |  |  | 61100AH00-012-G | RES,10KOhm,+/-0.5%,1/16W,G,SMD0402 | WALSIN | WF04U1002DTL |  | PWA BOM |  |
|  |  |  | 61100AH00-011-G | RES,10KOhm,+/-0.5%,1/16W,G,SMD0402 | YAGEO | RT0402DRE0710KL |  | PWA BOM |  |
|  |  |  | 61100AH00-044-G | RES,10KOhm,+/-0.5%,1/16W,G,SMD0402 | TA-I | RB04DTP1002 |  | PWA BOM |  |
| 32 | R1786,R1789,R1790,R1792,R1794,R1797,R1798,R1801,R1802,R1805,R1806,R1809,R1810,R1813,R1814,R1817,R1818,R1821,R1822,R1825,R1826,R1829,R1830 | 23 | 61010FG00-017-G | RES,20KOhm,+/-5%,1/16W,G,SMD0402 | KOA SPEER ELECTRONICS, INC. | RK73B1ETTP203J | N | PWA BOM |  |
|  |  |  | 61010FG00-012-G | RES,20KOhm,+/-5%,1/16W,G,SMD0402 | WALSIN TECHNOLOGY CORPORATION | WR04X203JTL | G | PWA BOM |  |
|  |  |  | 61010FG00-011-G | RES,20KOhm,+/-5%,1/16W,G,SMD0402 | YAGEO CORPORATION COMPONENT | RC0402JR-0720KL | G | PWA BOM |  |
| 33 | R1408,R1449 | 2 | 610107L00-017-G | RES,1 Ohm,+/-5%,1/10W,G,SMD0603 | KOA SPEER ELECTRONICS, INC. | RK73B1JTTD1R0J | N | PWA BOM |  |
| 34 | R2060 | 1 | 610154800-017-G | RES,1 Ohm,+/-5%,1/8W,G,SMD0402 | KOA SPEER ELECTRONICS, INC. | SG73P1ETTP1R0J |  | PWA BOM |  |
| 35 | U_Clock_B,U_Clock_A | 2 | 21050LL00-217-G | IC,IDT,9ZXL0831AKLFT,G,VFQFPN-48,SMD | INTEGRATED DEVICE TECHNOLOGY | 9ZXL0831AKLFT |  | PWA BOM |  |
| 36 | U_MUX1,U_MUX2,U_MUX3,U_MUX4,U_MUX5 | 5 | 31030CA00-031-G | IC,Switch,PCA9546APW,2.3~5.5V,G,TSSOP-16,SMD | NXP SEMICONDUCTORS | PCA9546APW | N | PWA BOM |  |
|  |  |  | 31030YF00-252-G | Logic IC,Switch,PI4MSD5V9546ALEX,1.65V~5.5V,0.3ns,TSSOP,16P,G | PERICOM SEMICONDUCTOR CORP | PI4MSD5V9546ALEX | G | PWA BOM |  |
| 37 | U_RESET | 1 | 32040P400-399-G | IC,Voltage sensor,SLG4N020VTR,G,TDFN-8,SMD | SILEGO | SLG4N020VTR |  | PWA BOM |  |
| 38 | U_SF2 | 1 | 21081NC00-432-G | IC,LSI,500021009,A2,G,TFBGA-141,SMD | LSI LOGIC CORPORATION | 500021009 |  | PWA BOM |  |
| 39 | U209,U229,U230,U231,U232,U233,U234,U235,U236,U237,U238,U239,U240,U241,U242,U243,U244,U245,U246,U247 | 20 | 310501200-183-G | IC,Buffer,SN74LVC1G07DCKR,1.65~5.5V,G,SC70-5,SMD | TEXAS INSTRUMENTS | SN74LVC1G07DCKR | N | PWA BOM |  |
| 40 | U248 | 1 | 220107K00-413-G | IC,PLD,10M02SCU169C8G,116MHz,3.3V,G,UBGA-169,SMD | ALTERA CORPORATION | 10M02SCU169C8G |  | PWA BOM |  |
| 41 | X7 | 1 | 71012HD00-100-G | XTAL,25MHz,+/-20ppm,8pF,G,SMD | TXC CORPORATION | 7V25000054 |  | PWA BOM |  |
| 42 | Y3 | 1 | 71020SH00-107-G | OSC,25MHz,+/-25ppm,3.3V,15pF,G,SMD | DAISHINKU CORPORATION/DAISHINKU SINGAPORE PTE LTD/KDS | 1XSE025000AR122 |  | PWA BOM |  |
| 43 | JPCIE1,JPCIE2,JPCIE3,JPCIE4,JPCIE5,JPCIE6,JPCIE7 | 7 | 340718900-245-G | CONN,SAS,V/T,0.6mm,30u,G,SMD-74 | AMPHENOL SHANGHAI CORP. | U10-B074-260T |  | PWA BOM |  |
| 44 | J_CPLD_JTAG | 1 | 3406B0G00-309-G | CONN,Header,Pin Header,2X5,V/T,Bla,2.54mm,10u,G,SMD-10 | SAMTEC INC. | TSM-105-04-L-DV-A-P-TR |  | PWA BOM |  |
| 45 | J_NVME01,J_NVME02,J_NVME03,J_NVME04,J_NVME05,J_NVME06,J_NVME07,J_NVME08,J_NVME09,J_NVME10,J_NVME11,J_NVME12,J_NVME13,J_NVME14,J_NVME15,J_NVME16,J_NVME17,J_NVME18,J_NVME19,J_NVME20,J_NVME21,J_NVME22,J_NVME23,J_NVME00 | 24 | 340313H00-600-G | CONN,PCIE,V/T,Bla,0.8mm,30u,G,SMD-68 | FOXCONN TECHNOLOGY CO.,LTD. | LU25683-A001-9H |  | PWA BOM |  |
| 46 | J1 | 1 | 3406B3H00-317-G | CONN,Header,Power,2X8,V/T,Bla,3mm,G,SMD-16 | MOLEX INCORPORATED | 43045-1618 | N | PWA BOM |  |
| ##### Remove Parts |  |  |  |  |  |  |  |  |  |
| Item | Location | Qty | Foxconn P/N | Part Description | Manufacturer Full Name | Manufacturer P/N | RoHS | Sheet |  |
| 1 | C225,C226,C227,C228,C229,C230,C231,C232,C233,C234,C235,C236,C237,C238,C239,C240,C241,C242,C243,C244,C245,C246,C247,C248 | 24 | 620101T02-015-G | CAP,100nF,+/-10%,X7R,16V,G,SMD0402 | MURATA ELEC. NORTH AMERICA | GRM155R71C104K | Y | PWA BOM |  |
|  |  |  | 620101T00-012-G | CAP,100nF,+/-10%,X7R,16V,G,SMD0402 | WALSIN | 0402B104K160CT |  | PWA BOM |  |
|  |  |  | 620101T00-026-G | CAP,100nF,+/-10%,X7R,16V,G,SMD0402 | SAMSUNG SEMICONDUCTOR | CL05B104KO5NNNC |  | PWA BOM |  |
|  |  |  | 620101T00-015-G | CAP,100nF,+/-10%,X7R,16V,G,SMD0402 | MURATA ELEC. NORTH AMERICA | GRM155R71C104KA88D |  | PWA BOM |  |
| 2 | PSRR8,R316,R325,R405,R421,R437,R453,R469,R485,R611,R627,R643,R659,R675,R691,R707,R723,R739,R755,R771,R787,R803,R819,R835,R851 | 25 | 610107A00-017-G | RES,0 Ohm,+/-5%,1/16W,G,SMD0402 | KOA SPEER ELECTRONICS, INC. | RK73Z1ETTP | N | PWA BOM |  |
|  |  |  | 610107A00-012-G | RES,0 Ohm,+/-5%,1/16W,G,SMD0402 | WALSIN | WR04X000PTL |  | PWA BOM |  |
|  |  |  | 610107A00-011-G | RES,0 Ohm,+/-5%,1/16W,G,SMD0402 | YAGEO | RC0402JR-070RL |  | PWA BOM |  |
|  |  |  | 610107A00-044-G | RES,0 Ohm,+/-5%,1/16W,G,SMD0402 | TA-I | RM04JTN0 |  | PWA BOM |  |
|  |  |  | 610107A00-024-G | RES,0 Ohm,+/-5%,1/16W,G,SMD0402 | PANASONIC INDUSTRIAL CO.,LTD. | ERJ2GE0R00X |  | PWA BOM |  |
|  |  |  | 610107A00-029-G | RES,0 Ohm,+/-5%,1/16W,G,SMD0402 | VISHAY ENTER TECHNO LOGY.INC | CRCW04020000Z0ED |  | PWA BOM |  |
| 3 | Q1,Q2,Q3,Q4,Q5,Q6,Q7,Q8,Q9,Q10,Q11,Q12,Q13,Q14,Q15,Q16,Q17,Q18,Q19,Q20,Q21,Q22,Q23,Q24 | 24 | 510301D00-223-G | MOS N,BSS138LT1G,50V,0.2A,3.5ohm@5V,G,SOT23-3,SMD | ON SEMICONDUCTOR CORP | BSS138LT1G | N | PWA BOM |  |
|  |  |  | 510309C00-237-G | MOS N,BSS138-7-F,50V,0.2A,3.5ohm@10V,G,SOT23-3,SMD | DIODES INCORPORATION | BSS138-7-F |  | PWA BOM |  |
|  |  |  | 510302R00-185-G | MOS N,BSS138,50V,0.22A,6ohm@4.5V,G,SOT23-3,SMD | FAIRCHILD SEMICONDUCTOR CORP | BSS138 |  | PWA BOM |  |
|  |  |  | 51030A800-221-G | MOS N,BSS138N,60V,0.23A,6ohm@4.5V,G,SOT23-3,SMD | INFINEON TECHNOLOGIES CORP. | BSS138N |  | PWA BOM |  |
| 4 | R322,R328,R408,R424,R440,R456,R472,R488,R587,R588,R589,R590,R591,R592,R593,R594,R595,R596,R597,R598,R599,R600,R601,R602,R603,R604,R605,R606,R607,R608,R609,R610,R614,R630,R646,R662,R678,R694,R710,R726,R742,R758,R774,R790,R806,R822,R838,R854 | 48 | 610107B00-017-G | RES,4.7KOhm,+/-5%,1/16W,G,SMD0402 | KOA SPEER ELECTRONICS, INC. | RK73B1ETTP472J | N | PWA BOM |  |
|  |  |  | 610107B00-012-G | RES,4.7KOhm,+/-5%,1/16W,G,SMD0402 | WALSIN | WR04X472JTL |  | PWA BOM |  |
|  |  |  | 610107B00-011-G | RES,4.7KOhm,+/-5%,1/16W,G,SMD0402 | YAGEO | RC0402JR-074K7L |  | PWA BOM |  |
|  |  |  | 610107B00-044-G | RES,4.7KOhm,+/-5%,1/16W,G,SMD0402 | TA-I | RM04JTN472 |  | PWA BOM |  |
|  |  |  | 610107B00-024-G | RES,4.7KOhm,+/-5%,1/16W,G,SMD0402 | PANASONIC INDUSTRIAL CO.,LTD. | ERJ2GEJ472X |  | PWA BOM |  |
|  |  |  | 610107B00-029-G | RES,4.7KOhm,+/-5%,1/16W,G,SMD0402 | VISHAY ENTER TECHNO LOGY.INC | CRCW04024K70JNED |  | PWA BOM |  |
| 5 | R870,R871,R872,R873,R922,R923,R924,R925,R926,R927,R928,R929,R930,R931 | 14 | 61011H100-017-G | RES,220 Ohm,+/-1%,1/16W,G,SMD0402 | KOA SPEER ELECTRONICS, INC. | RK73H1ETTP2200F | N | PWA BOM |  |
|  |  |  | 61011H100-012-G | RES,220 Ohm,+/-1%,1/16W,G,SMD0402 | WALSIN | WR04X2200FTL |  | PWA BOM |  |
|  |  |  | 61011H100-011-G | RES,220 Ohm,+/-1%,1/16W,G,SMD0402 | YAGEO | RC0402FR-07220RL |  | PWA BOM |  |
|  |  |  | 61011H100-044-G | RES,220 Ohm,+/-1%,1/16W,G,SMD0402 | TA-I | RM04FTN2200 |  | PWA BOM |  |
|  |  |  | 61011H100-024-G | RES,220 Ohm,+/-1%,1/16W,G,SMD0402 | PANASONIC INDUSTRIAL CO.,LTD. | ERJ2RKF2200X |  | PWA BOM |  |
|  |  |  | 61011H100-029-G | RES,220 Ohm,+/-1%,1/16W,G,SMD0402 | VISHAY ENTER TECHNO LOGY.INC | CRCW0402220RFKEDC |  | PWA BOM |  |
| 6 | U5,U6,U7,U8,U9,U10,U11,U12,U13,U14,U15,U16,U17,U18,U19,U20,U21,U22,U23,U24,U25,U26,U27,U28 | 24 | 310102400-183-G | IC,Gate&Inverter,SN74AHC1G32DBVR,2~5.5V,G,SOT23-5,SMD | TEXAS INSTRUMENTS | SN74AHC1G32DBVR | N | PWA BOM |  |
|  |  |  | 310106R00-185-G | IC,Gate&Inverter,NC7S32M5X,2~6V,G,SOT23-5,SMD | FAIRCHILD SEMICONDUCTOR CORP | NC7S32M5X |  | PWA BOM |  |
|  |  |  | 310106U00-031-G | IC,Gate&Inverter,74AHC1G32GV,2~5.5V,G,SC74A-5,SMD | NXP SEMICONDUCTORS | 74AHC1G32GV |  | PWA BOM |  |
| 7 | U30,U31,U32 | 3 | 21050LL00-217-G | IC,IDT,9ZXL0831AKLFT,G,VFQFPN-48,SMD | INTEGRATED DEVICE TECHNOLOGY | 9ZXL0831AKLFT |  | PWA BOM |  |
| 8 | J_BP_PWR1 | 1 | 3406B3H00-317-G | CONN,Header,Power,2X8,V/T,Bla,3mm,G,SMD-16 | MOLEX INCORPORATED | 43045-1618 | N | PWA BOM |  |
| 9 | H1,H2,H3,H4,H7,H8,H9,H10 | 8 | 2A5910Q00-HYM-G | SMT NUT,CARBON STEEL,G,FIVETECH,82-059-01-022-01-RL | Fivetech Technology Inc. | 82-059-01-022-01-RL |  | PWA BOM |  |
|  |  |  | 2A5914300-G44-G | 螺母,Nut,CARBON STEEL,N/A,4.7,3.5,7,TIN Plating,圓柱,G,00 | PennEngineering Fastening | YSMTSO-47670-ET |  | PWA BOM |  |
| 10 | JNVME_AUX1,JNVME_AUX2,JNVME_AUX3,JNVME_AUX4,JNVME_AUX5,JNVME_AUX6,JNVME_AUX7 | 7 | 340718900-245-G | CONN,SAS,V/T,0.6mm,30u,G,SMD-74 | AMPHENOL SHANGHAI CORP. | U10-B074-260T |  | PWA BOM |  |
| 11 | J_COMBODRV1,J_COMBODRV2,J_COMBODRV3,J_COMBODRV4,J_COMBODRV5,J_COMBODRV6,J_COMBODRV7,J_COMBODRV8,J_COMBODRV9,J_COMBODRV10,J_COMBODRV11,J_COMBODRV12,J_COMBODRV13,J_COMBODRV14,J_COMBODRV15,J_COMBODRV16,J_COMBODRV17,J_COMBODRV18,J_COMBODRV19,J_COMBODRV20,J_COMBODRV21,J_COMBODRV22,J_COMBODRV23,J_COMBODRV0 | 24 | 340313H00-600-G | CONN,PCIE,V/T,Bla,0.8mm,30u,G,SMD-68 | FOXCONN TECHNOLOGY CO.,LTD. | LU25683-A001-9H |  | PWA BOM |  |
| ##### Change Parts |  |  |  |  |  |  |  |  |  |
| Item | Location | Qty | Foxconn P/N | Part Description | Manufacturer Full Name | Manufacturer P/N | RoHS | Sheet | Remark |
| 1 | CE1 | 1 | 62111EC00-021-G | ECAP,680uF,+/-20%,16V,105℃,G,SMD10*10,ESR<=80mOhm | NIPPON CHEMI-CON CORPORATION | EMZA160ADA681MJA0G |  | PWA BOM | In New BOM |
|  |  |  | 62110EH00-024-G | ECAP,680uF,+/-20%,16V,105_x0003_,G,SMD10X10.2,ESR<=80mOhm | PANASONIC INDUSTRIAL CO.,LTD. | EEEFK1C681P |  | PWA BOM | In New BOM |
|  |  |  | 62111H200-018-G | ECAP,680uF,+/-20%,16V,105_x0003_,G,SMD10X10.5,ESR<=80mOhm | RUBYCON CORP. | 16TZV680M10X10.5 |  | PWA BOM | In New BOM |
|  | CE1 | 1 | 62111EC00-021-G | ECAP,680uF,+/-20%,16V,105℃,G,SMD10*10,ESR<=80mOhm | NIPPON CHEMI-CON CORPORATION | EMZA160ADA681MJA0G |  | PWA BOM | In Old BOM |
|  |  |  | 62110EH00-024-G | ECAP,680uF,+/-20%,16V,105℃,G,SMD10X10.2,ESR<=80mOhm | PANASONIC INDUSTRIAL CO.,LTD. | EEEFK1C681P |  | PWA BOM | In Old BOM |
|  |  |  | 62111H200-018-G | ECAP,680uF,+/-20%,16V,105℃,G,SMD10X10.5,ESR<=80mOhm | RUBYCON CORP. | 16TZV680M10X10.5 |  | PWA BOM | In Old BOM |
| 2 | LED37,LED39,LED49,LED51,LED53,LED55,LED57,LED59,LED61,LED63,LED65,LED67,LED69,LED71,LED73,LED75,LED77,LED79,LED81,LED83,LED85,LED87,LED89,LED91 | 24 | 52110LN00-289-G | LED,Gre,LTST-C191KGKT,2.4V,30mA,G,SMD0603 | LITE-ON TECHNOLOGY CORPORATION | LTST-C191KGKT |  | PWA BOM | In New BOM |
|  |  |  | 52110K100-030-G | LED LAMP,SML-512MWT86,Green,40mcd@If=20mA,N/A,5V,25mA,N/A,,SMD0603,2P,G | ROHM CORPORATION | SML-512MWT86 | G | PWA BOM | In New BOM |
|  | LED37,LED39,LED49,LED51,LED53,LED55,LED57,LED59,LED61,LED63,LED65,LED67,LED69,LED71,LED73,LED75,LED77,LED79,LED81,LED83,LED85,LED87,LED89,LED91 | 24 | 52110LN00-289-G | LED,Gre,LTST-C191KGKT,2.4V,30mA,G,SMD0603 | LITE-ON TECHNOLOGY CORPORATION | LTST-C191KGKT |  | PWA BOM | In Old BOM |
|  |  |  | 52110K100-030-G | LED LAMP,SML-512MWT86,Green,40mcd@If=20mA,N/A,5V,25mA,N/A,,SMD0603,2P,G | ROHM CORPORATION | SML-512MWT86 |  | PWA BOM | In Old BOM |
| 3 | L1 | 1 | 720101900-015-G | FB,60 Ohm@100MHz,+/-25%,3A,25mOhm,G,SMD0805 | MURATA ELEC. NORTH AMERICA | BLM21PG600SN1D | N | PWA BOM | In New BOM |
|  |  |  | 720101900-026-G | FB,60 Ohm@100MHz,+/-25%,3A,25mOhm,G,SMD0805 | SAMSUNG | CIC21P600NE | G | PWA BOM | In New BOM |
|  | L1 | 1 | 720101900-015-G | FB,60 Ohm@100MHz,+/-25%,3A,25mOhm,G,SMD0805 | MURATA ELEC. NORTH AMERICA | BLM21PG600SN1D | N | PWA BOM | In Old BOM |
|  |  |  | 720102E00-129-G | FB,60 Ohm@100MHz,+/-25%,3A,40mOhm,G,SMD0805 | MAG.LAYERS, SCIENTIFIC-TECHNICS (KUNSHAN) CO., LTD. | GMLB-201209-0060P-N8 |  | PWA BOM | In Old BOM |
|  |  |  | 720104100-074-G | FB,60 Ohm@100MHz,+/-25%,3A,30mOhm,G,SMD0805 | CHILISIN ELECTRONICS CORP. | PBY201209T-600Y-N |  | PWA BOM | In Old BOM |
| 4 | PSRC2,PSTC6,PFTC6,PETC6,PSTC7,PFTC7,PETC7,PSTC8,PFTC8,PETC8,PSTC9,PFTC9,PETC9,PSRC17,PSTC3005,PFTC3005,PETC3005,PSTC3006,PFTC3006,PETC3006,PSTC3007,PFTC3007,PETC3007,PSTC3010,PFTC3010,PETC3010,PSTC3011,PFTC3011,PETC3011,PSTC3012,PFTC3012,PETC3012,PSTC3013,PFTC3013,PETC3013,PFTC3014,PETC3014,PFTC3015,PETC3015,PFTC3016,PETC3016 | 41 | 62012T500-015-G | CAP,22uF,+/-20%,X7S,25V,G,SMD1206 | MURATA ELEC. NORTH AMERICA | GRM31CC71E226ME11L |  | PWA BOM | In New BOM |
|  | PSRC2,PSTC6,PFTC6,PETC6,PSTC7,PFTC7,PETC7,PSTC8,PFTC8,PETC8,PSTC9,PFTC9,PETC9,PSRC17,PSTC3005,PFTC3005,PETC3005,PSTC3006,PFTC3006,PETC3006,PSTC3007,PFTC3007,PETC3007,PSTC3010,PFTC3010,PETC3010,PSTC3011,PFTC3011,PETC3011,PSTC3012,PFTC3012,PETC3012,PSTC3013,PFTC3013,PETC3013,PFTC3014,PETC3014,PFTC3015,PETC3015,PFTC3016,PETC3016 | 41 | 62012T500-015-G | CAP,22uF,+/-20%,X7S,25V,G,SMD1206 | MURATA ELEC. NORTH AMERICA | GRM31CC71E226ME11L |  | PWA BOM | In Old BOM |
|  |  |  | 62012R900-026-G | CAP,22uF,+/-10%,X6S,25V,G,SMD1206 | SAMSUNG SEMICONDUCTOR | CL31X226KAHN3NE | G | PWA BOM | In Old BOM |
| 5 | PSTL1,PFTL1,PETL1 | 3 | 630335M00-088-G | IND,820nH@100KHz,+/-20%,13A,8mOhm,SHLD,G,SMD | COOPER BUSSMANN, INC. | HCM0703-R82-R |  | PWA BOM | In New BOM |
|  |  |  | 63035Y800-051-G | Coil Ind,Shielded(SHLD),820nH@100KHz,+/-20%,13A,8mOhm,SMD,7.6*6.9*3.0,,,G | PULSE ELECTRONICS (SINGAPORE) | PA4341.821NLT | G | PWA BOM | In New BOM |
|  |  |  | SPS-06CZ-R82M-V1 | Ind,SPS-06CZ-R82M-V1 | MAG.LAYERS, SCIENTIFIC-TECHNICS (KUNSHAN) CO., LTD. | SPS-06CZ-R82M-V1 | G | PWA BOM | In New BOM |
|  | PSTL1,PFTL1,PETL1 | 3 | 630335M00-088-G | IND,820nH@100KHz,+/-20%,13A,8mOhm,SHLD,G,SMD | COOPER BUSSMANN, INC. | HCM0703-R82-R |  | PWA BOM | In Old BOM |
|  |  |  | 63031F600-051-G | IND,820nH@100KHz,+/-20%,13A,8mOhm,SHLD,G,SMD | PULSE | PG0426.821NLT |  | PWA BOM | In Old BOM |
| 6 | PSTL2,PFTL2,PETL2 | 3 | 630341400-088-G | IND,22nH@1MHz,+/-20%,19A,368uOhm,SHLD,G,SMD | COOPER BUSSMANN, INC. | FP0404R1-R022-R |  | PWA BOM | In New BOM |
|  |  |  | HCB0430-220 | IND,HCB0430-220 | Delta | HCB0430-220 | G | PWA BOM | In New BOM |
|  | PSTL2,PFTL2,PETL2 | 3 | 630341400-088-G | IND,22nH@1MHz,+/-20%,19A,368uOhm,SHLD,G,SMD | COOPER BUSSMANN, INC. | FP0404R1-R022-R |  | PWA BOM | In Old BOM |
| 7 | PSRL2 | 1 | 63032PP00-088-G | IND,4.7uH@100KHz,+/-20%,5.5A,40mOhm,SHLD,G,SMD | COOPER BUSSMANN, INC. | HCM0703-4R7-R |  | PWA BOM | In New BOM |
|  |  |  | 63030PW00-034-G | Coil Ind,Shielded(SHLD),4.7uH@100KHz,+/-20%,5.5A,40mOhm,SMD,7.3*6.6*3.0,G | CYNTEC CO. LTD | PCMC063T-4R7MN | G | PWA BOM | In New BOM |
|  |  |  | SPS-06CZ-4R7M-V1 | IND,SPS-06CZ-4R7M-V1 | MAG.LAYERS, SCIENTIFIC-TECHNICS (KUNSHAN) CO., LTD. | SPS-06CZ-4R7M-V1 | G | PWA BOM | In New BOM |
|  | PSRL2 | 1 | 63032PP00-088-G | IND,4.7uH@100KHz,+/-20%,5.5A,40mOhm,SHLD,G,SMD | COOPER BUSSMANN, INC. | HCM0703-4R7-R |  | PWA BOM | In Old BOM |
|  |  |  | 63034RV00-15A-G | IND,4.7uH@100KHz,+/-20%,5.5A,40mOhm,SHLD,G,SMD | ITG | SMHC2511-4R7MHF |  | PWA BOM | In Old BOM |
| 8 | PSRR19 | 1 | 61100YB00-017-G | RES,2.94KOhm,+/-0.1%,1/16W,G,SMD0402 | KOA SPEER ELECTRONICS, INC. | RN731ETTP2941B25 |  | PWA BOM | In New BOM |
|  | PSRR19 | 1 | 61100YB00-017-G | RES,2.94KOhm,+/-0.1%,1/16W,G,SMD0402 | KOA SPEER ELECTRONICS, INC. | RN731ETTP2941B25 |  | PWA BOM | In Old BOM |
|  |  |  | 61100YB00-011-G | RES,2.94KOhm,+/-0.1%,1/16W,G,SMD0402 | YAGEO | RT0402BRD072K94L |  | PWA BOM | In Old BOM |
| 9 | U_AND1,U_AND2 | 2 | 310101400-031-G | IC,Gate&Inverter,74LVC1G08GW,1.65~5.5V,G,SOT353-5,SMD | NXP SEMICONDUCTORS | 74LVC1G08GW | N | PWA BOM | In New BOM |
|  |  |  | 310103J00-223-G | IC,Gate&Inverter,NL17SZ08DFT2G,1.65~5.5V,G,SOT353-5,SMD | ON SEMICONDUCTOR CORP | NL17SZ08DFT2G | G | PWA BOM | In New BOM |
|  |  |  | 31010J400-131-G | IC,Gate&Inverter,TC7SZ08FU,1.8~5.5V,G,SSOP-5,SMD | TOSHIBA ELECTRONICS ASIA LTD | TC7SZ08FU | G | PWA BOM | In New BOM |
|  | U_AND1,U_AND2 | 2 | 310101400-031-G | IC,Gate&Inverter,74LVC1G08GW,1.65~5.5V,G,SOT353-5,SMD | NXP SEMICONDUCTORS | 74LVC1G08GW | N | PWA BOM | In Old BOM |
|  |  |  | 310102100-183-G | IC,Gate&Inverter,SN74LVC1G08DCKR,1.65~5.5V,G,SOT323-5,SMD | TEXAS INSTRUMENTS | SN74LVC1G08DCKR |  | PWA BOM | In Old BOM |
|  |  |  | 310103J00-223-G | IC,Gate&Inverter,NL17SZ08DFT2G,1.65~5.5V,G,SOT353-5,SMD | ON SEMICONDUCTOR CORP | NL17SZ08DFT2G |  | PWA BOM | In Old BOM |
| 10 | U_I2C_RE1 | 1 | 311004800-031-G | IC,Translator,PCA9617ADPJ,0.8~5.5V,2.2~5.5V,G,TSSOP-8,SMD | NXP SEMICONDUCTORS | PCA9617ADPJ |  | PWA BOM | In New BOM |
|  |  |  | 311004V00-223-G | Logic IC,Translator,PCA9617ADMR2G,Vcca=0.8V~5.5V,Vccb=2.2V~5.5V,102ns,Micro8,8P,G | ON SEMICONDUCTOR CORP | PCA9617ADMR2G |  | PWA BOM | In New BOM |
|  | U_I2C_RE1 | 1 | 311004800-031-G | IC,Translator,PCA9617ADPJ,0.8~5.5V,2.2~5.5V,G,TSSOP-8,SMD | NXP SEMICONDUCTORS | PCA9617ADPJ |  | PWA BOM | In Old BOM |
|  |  |  | 311004V00-223-G | Logic IC,Translator,PCA9617ADMR2G,Vcca=0.8V~5.5V,Vccb=2.2V~5.5V,102ns,Micro8,8P,G | ON SEMICONDUCTOR CORP | PCA9617ADMR2G |  | PWA BOM | In Old BOM |
|  |  |  | 311004K00-183-G | Logic IC,Translator,TCA9617ADGKR,Vcca=0.8V~5.5V;Vccb=2.2V~5.5V,250ns,VSSOP,8P,G | TEXAS INSTRUMENTS | TCA9617ADGKR |  | PWA BOM | In Old BOM |
|  |  |  | 311004U00-252-G | Logic IC,Translator,PI6ULS5V9617AUEX,Vcca=0.8V~5.5V,Vccb=2.2V~5.5V,102ns,MSOP,8P,G | PERICOM SEMICONDUCTOR CORP | PI6ULS5V9617AUEX |  | PWA BOM | In Old BOM |
| 11 | U_TMP1 | 1 | 32040J800-183-G | IC,Temp Sensor,TMP75AIDGKR,N/A,G,MSOP-8,SMD | TEXAS INSTRUMENTS | TMP75AIDGKR | N | PWA BOM | In New BOM |
|  |  |  | 32040PJ00-223-G | IC,Temperature Sensor,NCT75DMR2G,G,MSOP-8,SMD | ON SEMICONDUCTOR CORP | NCT75DMR2G |  | PWA BOM | In New BOM |
|  | U_TMP1 | 1 | 32040J800-183-G | IC,Temp Sensor,TMP75AIDGKR,N/A,G,MSOP-8,SMD | TEXAS INSTRUMENTS | TMP75AIDGKR | N | PWA BOM | In Old BOM |
|  |  |  | 32040PJ00-223-G | IC,Temperature Sensor,NCT75DMR2G,G,MSOP-8,SMD | ON SEMICONDUCTOR CORP | NCT75DMR2G |  | PWA BOM | In Old BOM |
| 12 | PCB | 1 | PCB | PCB | PCB | PCB | G | PWA BOM | In New BOM |
|  | PCB | 1 | PCB | PCB | TBD | PCB | G | PWA BOM | In Old BOM |
| 13 | U_BP_FRU1 | 1 | 41040B600-191-G | EEPROM,AT24C02C-SSHM-T,1.7~5.5V,2K,I2C,G,SOIC-8,SMD | ATMEL CORPORATION | FP0404R1-R022-R | N | PWA BOM | In New BOM |
|  | U_BP_FRU1 | 1 | 41040HW00-191-G | EEPROM,AT24C02D-SSHM-T,1.7~3.6V,2K,I2C,G,SOIC-8,SMD | ATMEL CORPORATION | AT24C02D-SSHM-T |  | PWA BOM | In Old BOM |
|  |  |  | 32040PJ00-223-G | IC,Temperature Sensor,NCT75DMR2G,G,MSOP-8,SMD | ON SEMICONDUCTOR CORP | NCT75DMR2G |  | PWA BOM | In Old BOM |
| 14 | U29 | 1 | 9FGL0651BKILFT | IC,IDT,9FGL0651BKILFT,G,VFQFN-40,SMD | INTEGRATED DEVICE TECHNOLOGY | 9FGL0651BKILFT |  | PWA BOM | In New BOM |
|  | U29 | 1 | 21050Q500-217-G | IC,IDT,871S1022EKLFT,G,VFQFN-32,SMD | INTEGRATED DEVICE TECHNOLOGY | 871S1022EKLFT |  | PWA BOM | In Old BOM |
| ##### Change Revision |  |  |  |  |  |  |  |  |  |
| Sheet | REV OF BOM | CUSTOMER | CUSTOMER P/N | PWA PN | PWA DESCRIPTION | PWA REV | DATE | Remark |  |
| PWA BOM |  | Customer |  |  |  |  |  | In New BOM |  |
| PWA BOM | X00 | Customer |  |  |  | X00 | 4/20/17 | In Old BOM |  |
| OOOOOOOOOOOOOOOOOOOOOOOOOOOOOOOOOOOOOOOOOOOOOOOOOOOOOOOOOOOOOOOOOOOOOOOOOOOOOOOOOOOOOOOOOO | OOOOOOOOOOOOOOOOOOOOOOOOOOOOOOOOOOOOOOOOOOOOOOOOOOOOOOOOOOOOOOOOOOOOOOOOOOOOOOOOOOOOOOOOOO | OOOOOOOOOOOOOOOOOOOOOOOOOOOOOOOOOOOOOOOOOOOOOOOOOOOOOOOOOOOOOOOOOOOOOOOOOOOOOOOOOOOOOOOOOO | OOOOOOOOOOOOOOOOOOOOOOOOOOOOOOOOOOOOOOOOOOOOOOOOOOOOOOOOOOOOOOOOOOOOOOOOOOOOOOOOOOOOOOOOOO | OOOOOOOOOOOOOOOOOOOOOOOOOOOOOOOOOOOOOOOOOOOOOOOOOOOOOOOOOOOOOOOOOOOOOOOOOOOOOOOOOOOOOOOOOO | OOOOOOOOOOOOOOOOOOOOOOOOOOOOOOOOOOOOOOOOOOOOOOOOOOOOOOOOOOOOOOOOOOOOOOOOOOOOOOOOOOOOOOOOOO | OOOOOOOOOOOOOOOOOOOOOOOOOOOOOOOOOOOOOOOOOOOOOOOOOOOOOOOOOOOOOOOOOOOOOOOOOOOOOOOOOOOOOOOOOO | OOOOOOOOOOOOOOOOOOOOOOOOOOOOOOOOOOOOOOOOOOOOOOOOOOOOOOOOOOOOOOOOOOOOOOOOOOOOOOOOOOOOOOOOOO | OOOOOOOOOOOOOOOOOOOOOOOOOOOOOOOOOOOOOOOOOOOOOOOOOOOOOOOOOOOOOOOOOOOOOOOOOOOOOOOOOOOOOOOOOO | OOOOOOOOOOOOOOOOOOOOOOOOOOOOOOOOOOOOOOOOOOOOOOOOOOOOOOOOOOOOOOOOOOOOOOOOOOOOOOOOOOOOOOOOOO |
| Second Source Change |  |  |  |  |  |  |  |  |  |
| Item | Location | Change Type | Foxconn P/N | Part Description | Manufacturer Full Name | Manufacturer P/N | RoHS | Sheet |  |
| 1 | L1 |  | 720101900-015-G | FB,60 Ohm@100MHz,+/-25%,3A,25mOhm,G,SMD0805 | MURATA ELEC. NORTH AMERICA | BLM21PG600SN1D | N | PWA BOM |  |
|  |  | ADD | 720101900-026-G | FB,60 Ohm@100MHz,+/-25%,3A,25mOhm,G,SMD0805 | SAMSUNG | CIC21P600NE | G | PWA BOM |  |
|  |  | Delete | 720102E00-129-G | FB,60 Ohm@100MHz,+/-25%,3A,40mOhm,G,SMD0805 | MAG.LAYERS, SCIENTIFIC-TECHNICS (KUNSHAN) CO., LTD. | GMLB-201209-0060P-N8 |  | PWA BOM |  |
|  |  | Delete | 720104100-074-G | FB,60 Ohm@100MHz,+/-25%,3A,30mOhm,G,SMD0805 | CHILISIN ELECTRONICS CORP. | PBY201209T-600Y-N |  | PWA BOM |  |
| 2 | PSRC2,PSTC6,PFTC6,PETC6,PSTC7,PFTC7,PETC7,PSTC8,PFTC8,PETC8,PSTC9,PFTC9,PETC9,PSRC17,PSTC3005,PFTC3005,PETC3005,PSTC3006,PFTC3006,PETC3006,PSTC3007,PFTC3007,PETC3007,PSTC3010,PFTC3010,PETC3010,PSTC3011,PFTC3011,PETC3011,PSTC3012,PFTC3012,PETC3012,PSTC3013,PFTC3013,PETC3013,PFTC3014,PETC3014,PFTC3015,PETC3015,PFTC3016,PETC3016 |  | 62012T500-015-G | CAP,22uF,+/-20%,X7S,25V,G,SMD1206 | MURATA ELEC. NORTH AMERICA | GRM31CC71E226ME11L |  | PWA BOM |  |
|  |  | Delete | 62012R900-026-G | CAP,22uF,+/-10%,X6S,25V,G,SMD1206 | SAMSUNG SEMICONDUCTOR | CL31X226KAHN3NE | G | PWA BOM |  |
| 3 | PSTL1,PFTL1,PETL1 |  | 630335M00-088-G | IND,820nH@100KHz,+/-20%,13A,8mOhm,SHLD,G,SMD | COOPER BUSSMANN, INC. | HCM0703-R82-R |  | PWA BOM |  |
|  |  | ADD | 63035Y800-051-G | Coil Ind,Shielded(SHLD),820nH@100KHz,+/-20%,13A,8mOhm,SMD,7.6*6.9*3.0,,,G | PULSE ELECTRONICS (SINGAPORE) | PA4341.821NLT | G | PWA BOM |  |
|  |  | ADD | SPS-06CZ-R82M-V1 | Ind,SPS-06CZ-R82M-V1 | MAG.LAYERS, SCIENTIFIC-TECHNICS (KUNSHAN) CO., LTD. | SPS-06CZ-R82M-V1 | G | PWA BOM |  |
|  |  | Delete | 63031F600-051-G | IND,820nH@100KHz,+/-20%,13A,8mOhm,SHLD,G,SMD | PULSE | PG0426.821NLT |  | PWA BOM |  |
| 4 | PSTL2,PFTL2,PETL2 |  | 630341400-088-G | IND,22nH@1MHz,+/-20%,19A,368uOhm,SHLD,G,SMD | COOPER BUSSMANN, INC. | FP0404R1-R022-R |  | PWA BOM |  |
|  |  | ADD | HCB0430-220 | IND,HCB0430-220 | Delta | HCB0430-220 | G | PWA BOM |  |
| 5 | PSRL2 |  | 63032PP00-088-G | IND,4.7uH@100KHz,+/-20%,5.5A,40mOhm,SHLD,G,SMD | COOPER BUSSMANN, INC. | HCM0703-4R7-R |  | PWA BOM |  |
|  |  | ADD | 63030PW00-034-G | Coil Ind,Shielded(SHLD),4.7uH@100KHz,+/-20%,5.5A,40mOhm,SMD,7.3*6.6*3.0,G | CYNTEC CO. LTD | PCMC063T-4R7MN | G | PWA BOM |  |
|  |  | ADD | SPS-06CZ-4R7M-V1 | IND,SPS-06CZ-4R7M-V1 | MAG.LAYERS, SCIENTIFIC-TECHNICS (KUNSHAN) CO., LTD. | SPS-06CZ-4R7M-V1 | G | PWA BOM |  |
|  |  | Delete | 63034RV00-15A-G | IND,4.7uH@100KHz,+/-20%,5.5A,40mOhm,SHLD,G,SMD | ITG | SMHC2511-4R7MHF |  | PWA BOM |  |
| 6 | PSRR19 |  | 61100YB00-017-G | RES,2.94KOhm,+/-0.1%,1/16W,G,SMD0402 | KOA SPEER ELECTRONICS, INC. | RN731ETTP2941B25 |  | PWA BOM |  |
|  |  | Delete | 61100YB00-011-G | RES,2.94KOhm,+/-0.1%,1/16W,G,SMD0402 | YAGEO | RT0402BRD072K94L |  | PWA BOM |  |
| 7 | U_AND1,U_AND2 |  | 310101400-031-G | IC,Gate&Inverter,74LVC1G08GW,1.65~5.5V,G,SOT353-5,SMD | NXP SEMICONDUCTORS | 74LVC1G08GW | N | PWA BOM |  |
|  |  | NO | 310103J00-223-G | IC,Gate&Inverter,NL17SZ08DFT2G,1.65~5.5V,G,SOT353-5,SMD | ON SEMICONDUCTOR CORP | NL17SZ08DFT2G | G | PWA BOM |  |
|  |  | ADD | 31010J400-131-G | IC,Gate&Inverter,TC7SZ08FU,1.8~5.5V,G,SSOP-5,SMD | TOSHIBA ELECTRONICS ASIA LTD | TC7SZ08FU | G | PWA BOM |  |
|  |  | Delete | 310102100-183-G | IC,Gate&Inverter,SN74LVC1G08DCKR,1.65~5.5V,G,SOT323-5,SMD | TEXAS INSTRUMENTS | SN74LVC1G08DCKR |  | PWA BOM |  |
| 8 | U_I2C_RE1 |  | 311004800-031-G | IC,Translator,PCA9617ADPJ,0.8~5.5V,2.2~5.5V,G,TSSOP-8,SMD | NXP SEMICONDUCTORS | PCA9617ADPJ |  | PWA BOM |  |
|  |  | NO | 311004V00-223-G | Logic IC,Translator,PCA9617ADMR2G,Vcca=0.8V~5.5V,Vccb=2.2V~5.5V,102ns,Micro8,8P,G | ON SEMICONDUCTOR CORP | PCA9617ADMR2G |  | PWA BOM |  |
|  |  | Delete | 311004K00-183-G | Logic IC,Translator,TCA9617ADGKR,Vcca=0.8V~5.5V;Vccb=2.2V~5.5V,250ns,VSSOP,8P,G | TEXAS INSTRUMENTS | TCA9617ADGKR |  | PWA BOM |  |
|  |  | Delete | 311004U00-252-G | Logic IC,Translator,PI6ULS5V9617AUEX,Vcca=0.8V~5.5V,Vccb=2.2V~5.5V,102ns,MSOP,8P,G | PERICOM SEMICONDUCTOR CORP | PI6ULS5V9617AUEX |  | PWA BOM |  |
| 9 | U_TMP1 |  | 32040J800-183-G | IC,Temp Sensor,TMP75AIDGKR,N/A,G,MSOP-8,SMD | TEXAS INSTRUMENTS | TMP75AIDGKR | N | PWA BOM |  |
|  |  | ADD | 32040PJ00-223-G | IC,Temperature Sensor,NCT75DMR2G,G,MSOP-8,SMD | ON SEMICONDUCTOR CORP | NCT75DMR2G |  | PWA BOM |  |
|  |  | Delete | 32040PJ00-223-G | IC,Temperature Sensor,NCT75DMR2G,G,MSOP-8,SMD | ON SEMICONDUCTOR CORP | NCT75DMR2G |  | PWA BOM |  |
| OOOOOOOOOOOOOOOOOOOOOOOOOOOOOOOOOOOOOOOOOOOOOOOOOOOOOOOOOOOOOOOOOOOOOOOOOOOOOOOOOOOOOOOOOO | OOOOOOOOOOOOOOOOOOOOOOOOOOOOOOOOOOOOOOOOOOOOOOOOOOOOOOOOOOOOOOOOOOOOOOOOOOOOOOOOOOOOOOOOOO | OOOOOOOOOOOOOOOOOOOOOOOOOOOOOOOOOOOOOOOOOOOOOOOOOOOOOOOOOOOOOOOOOOOOOOOOOOOOOOOOOOOOOOOOOO | OOOOOOOOOOOOOOOOOOOOOOOOOOOOOOOOOOOOOOOOOOOOOOOOOOOOOOOOOOOOOOOOOOOOOOOOOOOOOOOOOOOOOOOOOO | OOOOOOOOOOOOOOOOOOOOOOOOOOOOOOOOOOOOOOOOOOOOOOOOOOOOOOOOOOOOOOOOOOOOOOOOOOOOOOOOOOOOOOOOOO | OOOOOOOOOOOOOOOOOOOOOOOOOOOOOOOOOOOOOOOOOOOOOOOOOOOOOOOOOOOOOOOOOOOOOOOOOOOOOOOOOOOOOOOOOO | OOOOOOOOOOOOOOOOOOOOOOOOOOOOOOOOOOOOOOOOOOOOOOOOOOOOOOOOOOOOOOOOOOOOOOOOOOOOOOOOOOOOOOOOOO | OOOOOOOOOOOOOOOOOOOOOOOOOOOOOOOOOOOOOOOOOOOOOOOOOOOOOOOOOOOOOOOOOOOOOOOOOOOOOOOOOOOOOOOOOO | OOOOOOOOOOOOOOOOOOOOOOOOOOOOOOOOOOOOOOOOOOOOOOOOOOOOOOOOOOOOOOOOOOOOOOOOOOOOOOOOOOOOOOOOOO | OOOOOOOOOOOOOOOOOOOOOOOOOOOOOOOOOOOOOOOOOOOOOOOOOOOOOOOOOOOOOOOOOOOOOOOOOOOOOOOOOOOOOOOOOO |
| Master Materials Change |  |  |  |  |  |  |  |  |  |
| Item | Foxconn P/N | Orig._Usage | New_Usage | Part Description | Manufacturer Full Name | Manufacturer P/N | RoHS | Location | Sheet |
| 1 | 620101T02-015-G | 90 | 164 | CAP,100nF,+/-10%,X7R,16V,G,SMD0402 | MURATA ELEC. NORTH AMERICA | GRM155R71C104K | Y | (+)C15,C19,C216,C217,C224,C2101,C2102,C2103,C2104,C2105,C2106,C2107,C2108,C2109,C2110,C2111,C2112,C2113,C2114,C2115,C2116,C2117,C2118,C2119,C2120,C2121,C2122,C2123,C2124,C2125,C2126,C2127,C2128,C2129,C2130,C2131,C2132,C2133,C2134,C2135,C2136,C2137,C2138,C2139,C2140,C2141,C2142,C2143,C2144,C2145,C2146,C2147,C2148,C2149,C2169,C2171,C2176,C2177,C2178,C2179,C2180,C2181,C2182,C2183,C2184,C2185,C2186,C2187,C2188,C2189,C2190,C2191,C2192,C2193,C2194,C2195,C2196,C2197,C2232,C2233,C2234,C2235,C2237,C2239,C2240,C2241,C2242,C2254,C2255,C2256,C2259,C2260,C2261,C2262,C2263,C2264,C2265,C2266 (-)C225,C226,C227,C228,C229,C230,C231,C232,C233,C234,C235,C236,C237,C238,C239,C240,C241,C242,C243,C244,C245,C246,C247,C248 | PWA BOM |
|  | 620101T00-012-G |  |  | CAP,100nF,+/-10%,X7R,16V,G,SMD0402 | WALSIN | 0402B104K160CT |  |  | PWA BOM |
|  | 620101T00-026-G |  |  | CAP,100nF,+/-10%,X7R,16V,G,SMD0402 | SAMSUNG SEMICONDUCTOR | CL05B104KO5NNNC |  |  | PWA BOM |
|  | 620101T00-015-G |  |  | CAP,100nF,+/-10%,X7R,16V,G,SMD0402 | MURATA ELEC. NORTH AMERICA | GRM155R71C104KA88D |  |  | PWA BOM |
| 2 | 620100A00-015-G | 28 | 30 | CAP,10uF,+/-10%,X5R,16V,G,SMD1206 | MURATA ELEC. NORTH AMERICA | GRM31CR61C106K | N | (+)C2236,C2238 | PWA BOM |
|  | 620100A00-026-G |  |  | CAP,10uF,+/-10%,X5R,16V,G,SMD1206 | SAMSUNG SEMICONDUCTOR | CL31A106KOHNNNE |  |  | PWA BOM |
|  | 620100A03-023-G |  |  | CAP,10uF,+/-10%,X5R,16V,G,SMD1206 | TAIYO ELECTRIC IND.CO.LTD | EMK316BJ106KL-T |  |  | PWA BOM |
|  | 620100A00-012-G |  |  | CAP,10uF,+/-10%,X5R,16V,G,SMD1206 | WALSIN TECHNOLOGY CORPORATION | 1206X106K160CT |  |  | PWA BOM |
|  | 620100A00-011-G |  |  | CAP,10uF,+/-10%,X5R,16V,G,SMD1206 | YAGEO CORPORATION COMPONENT | CC1206KKX5R7BB106 |  |  | PWA BOM |
| 3 | 620105E00-015-G | 1 | 2 | CAP,1uF,+/-10%,X7R,10V,G,SMD0603 | MURATA ELEC. NORTH AMERICA | GRM188R71A105K |  | (+)C215 | PWA BOM |
|  | 620105E00-012-G |  |  | CAP,1uF,+/-10%,X7R,10V,G,SMD0603 | WALSIN TECHNOLOGY CORPORATION | 0603B105K100CT |  |  | PWA BOM |
|  | 620105E00-011-G |  |  | CAP,1uF,+/-10%,X7R,10V,G,SMD0603 | YAGEO CORPORATION COMPONENT | CC0603KRX7R6BB105 |  |  | PWA BOM |
|  | 620105E00-026-G |  |  | CAP,1uF,+/-10%,X7R,10V,G,SMD0603 | SAMSUNG SEMICONDUCTOR | CL10B105KP8NNNC |  |  | PWA BOM |
|  | 620105E01-023-G |  |  | CAP,1uF,+/-10%,X7R,10V,G,SMD0603 | TAIYO ELECTRIC IND.CO.LTD | LMK107B7105KA-T |  |  | PWA BOM |
| 4 | 620103600-015-G | 5 | 14 | CAP,10nF,+/-10%,X7R,25V,G,SMD0402 | MURATA ELEC. NORTH AMERICA | GRM155R71E103K | N | (+)C218,C219,C220,C221,C222,C2243,C2244,C2251,C2252 | PWA BOM |
|  | 620103600-012-G |  |  | CAP,10nF,+/-10%,X7R,25V,G,SMD0402 | WALSIN TECHNOLOGY CORPORATION | 0402B103K250CT |  |  | PWA BOM |
|  | 620103600-011-G |  |  | CAP,10nF,+/-10%,X7R,25V,G,SMD0402 | YAGEO CORPORATION COMPONENT | CC0402KRX7R8BB103 |  |  | PWA BOM |
|  | 620103600-026-G |  |  | CAP,10nF,+/-10%,X7R,25V,G,SMD0402 | SAMSUNG SEMICONDUCTOR | CL05B103KA5NNNC |  |  | PWA BOM |
|  | 620103601-023-G |  |  | CAP,10nF,+/-10%,X7R,25V,G,SMD0402 | TAIYO ELECTRIC IND.CO.LTD | TMK105B7103KV-F |  |  | PWA BOM |
| 5 | 62010L000-015-G | 1 | 2 | CAP,10uF,+/-20%,X5R,6.3V,G,SMD0603 | MURATA ELEC. NORTH AMERICA | GRM188R60J106M | N | (+)C214 | PWA BOM |
|  | 62010L000-023-G |  |  | CAP,10uF,+/-20%,X5R,6.3V,G,SMD0603 | TAIYO ELECTRIC IND.CO.LTD | JMK107BJ106MA-T |  |  | PWA BOM |
|  | 62010L000-012-G |  |  | CAP,10uF,+/-20%,X5R,6.3V,G,SMD0603 | WALSIN TECHNOLOGY CORPORATION | 0603X106M6R3CT |  |  | PWA BOM |
|  | 62010L000-026-G |  |  | CAP,10uF,+/-20%,X5R,6.3V,G,SMD0603 | SAMSUNG SEMICONDUCTOR | CL10A106MQ8NNNC |  |  | PWA BOM |
|  | 62010L000-011-G |  |  | CAP,10uF,+/-20%,X5R,6.3V,G,SMD0603 | YAGEO CORPORATION COMPONENT | CC0603MRX5R5BB106 |  |  | PWA BOM |
| 6 | 62011NF01-015-G | 1 | 2 | CAP,2.2uF,+/-10%,X7R,25V,G,SMD0805 | MURATA ELEC. NORTH AMERICA | GRM21BR71E225K |  | (+)C223 | PWA BOM |
|  | 62011NF00-026-G |  |  | CAP,2.2uF,+/-10%,X7R,25V,G,SMD0805 | SAMSUNG SEMICONDUCTOR | CL21B225KAFNNNE |  |  | PWA BOM |
|  | 62011NF00-023-G |  |  | CAP,2.2uF,+/-10%,X7R,25V,G,SMD0805 | TAIYO ELECTRIC IND.CO.LTD | TMK212B7225KG-TR |  |  | PWA BOM |
| 7 | 620114000-015-G | 0 | 3 | CAP,10uF,+/-10%,X5R,16V,G,SMD0805 | MURATA ELEC. NORTH AMERICA | GRM21BR61C106K | N | (+)C1946,C2081,C2253 | PWA BOM |
| 8 | 620105400-015-G | 0 | 10 | CAP,1uF,+/-10%,X7R,16V,G,SMD0603 | MURATA ELEC. NORTH AMERICA | GRM188R71C105K | N | (+)C1950,C2080,C2245,C2246,C2247,C2248,C2249,C2250,C2257,C2258 | PWA BOM |
|  | 620105400-012-G |  |  | CAP,1uF,+/-10%,X7R,16V,G,SMD0603 | WALSIN TECHNOLOGY CORPORATION | 0603B105K160CT |  |  | PWA BOM |
|  | 620105400-011-G |  |  | CAP,1uF,+/-10%,X7R,16V,G,SMD0603 | YAGEO CORPORATION COMPONENT | CC0603KRX7R7BB105 |  |  | PWA BOM |
|  | 620105400-026-G |  |  | CAP,1uF,+/-10%,X7R,16V,G,SMD0603 | SAMSUNG SEMICONDUCTOR | CL10B105KO8NNNC |  |  | PWA BOM |
|  | 620105400-023-G |  |  | CAP,1uF,+/-10%,X7R,16V,G,SMD0603 | TAIYO ELECTRIC IND.CO.LTD | EMK107B7105KA-T |  |  | PWA BOM |
| 9 | 62011LU00-015-G | 0 | 18 | CAP,100nF,+/-10%,X5R,16V,G,SMD0402 | MURATA ELEC. NORTH AMERICA | GRM155R61C104KA88D | Y | (+)C2198,C2208,C2209,C2210,C2211,C2212,C2213,C2214,C2215,C2216,C2217,C2218,C2219,C2220,C2221,C2222,C2223,C2224 | PWA BOM |
| 10 | 620109S00-015-G | 0 | 1 | CAP,4.7uF,+/-10%,X7R,10V,G,SMD0805 | MURATA ELEC. NORTH AMERICA | GRM21BR71A475K | N | (+)C2231 | PWA BOM |
|  | 620109S00-023-G |  |  | CAP,4.7uF,+/-10%,X7R,10V,G,SMD0805 | TAIYO ELECTRIC IND.CO.LTD | LMK212B7475KG-T |  |  | PWA BOM |
|  | 620109S00-026-G |  |  | CAP,4.7uF,+/-10%,X7R,10V,G,SMD0805 | SAMSUNG SEMICONDUCTOR | CL21B475KPFNNNE |  |  | PWA BOM |
| 11 | 620106200-015-G | 0 | 1 | CAP,10nF,+/-10%,X7R,16V,G,SMD0402 | MURATA ELEC. NORTH AMERICA | GRM155R71C103K | N | (+)C2267 | PWA BOM |
|  | 620106200-012-G |  |  | CAP,10nF,+/-10%,X7R,16V,G,SMD0402 | WALSIN | 0402B103K160CT |  |  | PWA BOM |
|  | 620106200-026-G |  |  | CAP,10nF,+/-10%,X7R,16V,G,SMD0402 | SAMSUNG | CL05B103KO5NNNC |  |  | PWA BOM |
|  | 620106200-023-G |  |  | CAP,10nF,+/-10%,X7R,16V,G,SMD0402 | TAIYO | EMK105B7103KV-F |  |  | PWA BOM |
| 12 | 62012UW00-015-G | 0 | 2 | CAP,6.8pF,+/-0.05pF,NPO(C0G),25V,G,SMD0402 | MURATA ELEC. NORTH AMERICA | GRM1555C1E6R8WA01D |  | (+)C2268,C2269 | PWA BOM |
| 13 | 72010JY00-015-G | 1 | 2 | FB,330 Ohm@100MHz,+/-25%,1.5A,70mOhm,G,SMD0603 | MURATA ELEC. NORTH AMERICA | BLM18SG331TN1D | N | (+)L4 | PWA BOM |
|  | 72010JB00-016-G |  |  | FB,330 Ohm@100MHz,+/-25%,1.5A,G,80mOhm,SMD0603 | TDK ELECTRONICS EUROPE GMBH | MPZ1608S331AT |  |  | PWA BOM |
| 14 | 72010FB01-016-G | 0 | 2 | FB,600 Ohm@100MHz,+/-25%,1A,150mOhm,G,SMD0603 | TDK ELECTRONICS EUROPE GMBH | MPZ1608S601AT | N | (+)L6,L28 | PWA BOM |
| 15 | 720102001-015-G | 0 | 1 | FB,30 Ohm@100MHz,+/-25%,3A,15mOhm,G,SMD0805 | MURATA ELEC. NORTH AMERICA | BLM21PG300SN1D | N | (+)L30 | PWA BOM |
| 16 | 720101L00-015-G | 0 | 1 | FB,600 Ohm@100MHz,+/-25%,200mA,500mOhm,G,SMD0603 | MURATA ELEC. NORTH AMERICA | BLM18AG601SN1D | N | (+)L31 | PWA BOM |
| 17 | 61010LA00-017-G | 3 | 84 | RES,4.7KOhm,+/-1%,1/16W,G,SMD0402 | KOA SPEER ELECTRONICS, INC. | RK73H1ETTP4701F | N | (+)R336,R1605,R1700,R1701,R1702,R1703,R1704,R1705,R1706,R1707,R1708,R1709,R1710,R1711,R1712,R1713,R1714,R1715,R1716,R1717,R1718,R1719,R1720,R1721,R1722,R1723,R1724,R1725,R1726,R1727,R1728,R1729,R1730,R1731,R1732,R1733,R1734,R1735,R1736,R1737,R1738,R1739,R1831,R1832,R1834,R1835,R1837,R1838,R1840,R1841,R1843,R1844,R1846,R1847,R1849,R1850,R1852,R1853,R1855,R1856,R1858,R1859,R1861,R1862,R1864,R1865,R1867,R1868,R1870,R1871,R1873,R1874,R1876,R1877,R1879,R1880,R1882,R1883,R1885,R1886,R2065 | PWA BOM |
|  | 61010LA00-012-G |  |  | RES,4.7KOhm,+/-1%,1/16W,G,SMD0402 | WALSIN | WR04X4701FTL |  |  | PWA BOM |
|  | 61010LA00-011-G |  |  | RES,4.7KOhm,+/-1%,1/16W,G,SMD0402 | YAGEO | RC0402FR-074K7L |  |  | PWA BOM |
|  | 61010LA00-044-G |  |  | RES,4.7KOhm,+/-1%,1/16W,G,SMD0402 | TA-I | RM04FTN4701 |  |  | PWA BOM |
| 18 | 610107A00-017-G | 57 | 120 | RES,0 Ohm,+/-5%,1/16W,G,SMD0402 | KOA SPEER ELECTRONICS, INC. | RK73Z1ETTP | N | (+)R60,R65,R568,R569,R570,R571,R1888,R1889,R1890,R1891,R1892,R1893,R1894,R1895,R1896,R1897,R1898,R1899,R1900,R1901,R1902,R1903,R1988,R1989,R1990,R1991,R1992,R1993,R1994,R1995,R1996,R1997,R1998,R1999,R2000,R2001,R2002,R2003,R2004,R2005,R2006,R2007,R2008,R2009,R2010,R2011,R2012,R2013,R2014,R2015,R2016,R2017,R2018,R2019,R2020,R2021,R2022,R2023,R2024,R2025,R2026,R2027,R2028,R2029,R2030,R2031,R2032,R2033,R2034,R2035,R2036,R2037,R2038,R2039,R2040,R2041,R2042,R2043,R2044,R2045,R2046,R2047,R2061,R2066,R2067,R2068,R2069,R2070 (-)PSRR8,R316,R325,R405,R421,R437,R453,R469,R485,R611,R627,R643,R659,R675,R691,R707,R723,R739,R755,R771,R787,R803,R819,R835,R851 | PWA BOM |
|  | 610107A00-012-G |  |  | RES,0 Ohm,+/-5%,1/16W,G,SMD0402 | WALSIN | WR04X000PTL |  |  | PWA BOM |
|  | 610107A00-011-G |  |  | RES,0 Ohm,+/-5%,1/16W,G,SMD0402 | YAGEO | RC0402JR-070RL |  |  | PWA BOM |
|  | 610107A00-044-G |  |  | RES,0 Ohm,+/-5%,1/16W,G,SMD0402 | TA-I | RM04JTN0 |  |  | PWA BOM |
|  | 610107A00-024-G |  |  | RES,0 Ohm,+/-5%,1/16W,G,SMD0402 | PANASONIC INDUSTRIAL CO.,LTD. | ERJ2GE0R00X |  |  | PWA BOM |
|  | 610107A00-029-G |  |  | RES,0 Ohm,+/-5%,1/16W,G,SMD0402 | VISHAY ENTER TECHNO LOGY.INC | CRCW04020000Z0ED |  |  | PWA BOM |
| 19 | 61011H500-017-G | 6 | 30 | RES,22 Ohm,+/-1%,1/16W,G,SMD0402 | KOA SPEER ELECTRONICS, INC. | RK73H1ETTP22R0F | N | (+)R338,R550,R552,R868,R869,R1833,R1836,R1839,R1842,R1845,R1848,R1851,R1854,R1857,R1860,R1863,R1866,R1869,R1872,R1875,R1878,R1881,R1884,R1887 | PWA BOM |
|  | 61011H500-012-G |  |  | RES,22 Ohm,+/-1%,1/16W,G,SMD0402 | WALSIN | WR04X22R0FTL |  |  | PWA BOM |
|  | 61011H500-011-G |  |  | RES,22 Ohm,+/-1%,1/16W,G,SMD0402 | YAGEO | RC0402FR-0722RL |  |  | PWA BOM |
|  | 61011H500-044-G |  |  | RES,22 Ohm,+/-1%,1/16W,G,SMD0402 | TA-I | RM04FTN22R0 |  |  | PWA BOM |
|  | 61011H500-024-G |  |  | RES,22 Ohm,+/-1%,1/16W,G,SMD0402 | PANASONIC INDUSTRIAL CO.,LTD. | ERJ2RKF22R0X |  |  | PWA BOM |
| 20 | 610107B00-017-G | 138 | 152 | RES,4.7KOhm,+/-5%,1/16W,G,SMD0402 | KOA SPEER ELECTRONICS, INC. | RK73B1ETTP472J | N | (+)R50,R51,R52,R53,R62,R96,R97,R546,R547,R548,R549,R553,R555,R556,R557,R559,R560,R866,R1078,R1079,R1569,R1570,R1571,R1572,R1573,R1574,R1575,R1576,R1577,R1578,R1579,R1580,R1581,R1582,R1583,R1584,R1585,R1586,R1587,R1588,R1589,R1590,R1591,R1592,R1593,R1594,R1595,R1596,R1597,R1598,R1599,R1600,R1601,R1602,R1603,R1668,R1681,R1684,R1688,R1694,R1697,R1783 (-)R322,R328,R408,R424,R440,R456,R472,R488,R587,R588,R589,R590,R591,R592,R593,R594,R595,R596,R597,R598,R599,R600,R601,R602,R603,R604,R605,R606,R607,R608,R609,R610,R614,R630,R646,R662,R678,R694,R710,R726,R742,R758,R774,R790,R806,R822,R838,R854 | PWA BOM |
|  | 610107B00-012-G |  |  | RES,4.7KOhm,+/-5%,1/16W,G,SMD0402 | WALSIN | WR04X472JTL |  |  | PWA BOM |
|  | 610107B00-011-G |  |  | RES,4.7KOhm,+/-5%,1/16W,G,SMD0402 | YAGEO | RC0402JR-074K7L |  |  | PWA BOM |
|  | 610107B00-044-G |  |  | RES,4.7KOhm,+/-5%,1/16W,G,SMD0402 | TA-I | RM04JTN472 |  |  | PWA BOM |
|  | 610107B00-024-G |  |  | RES,4.7KOhm,+/-5%,1/16W,G,SMD0402 | PANASONIC INDUSTRIAL CO.,LTD. | ERJ2GEJ472X |  |  | PWA BOM |
|  | 610107B00-029-G |  |  | RES,4.7KOhm,+/-5%,1/16W,G,SMD0402 | VISHAY ENTER TECHNO LOGY.INC | CRCW04024K70JNED |  |  | PWA BOM |
| 21 | 61010JY00-017-G | 2 | 10 | RES,220 Ohm,+/-5%,1/16W,G,SMD0402 | KOA SPEER ELECTRONICS, INC. | RK73B1ETTP221J | N | (+)R1672,R1673,R1679,R1683,R1687,R1698,R1780,R1782 | PWA BOM |
|  | 61010JY00-012-G |  |  | RES,220 Ohm,+/-5%,1/16W,G,SMD0402 | WALSIN | WR04X221JTL |  |  | PWA BOM |
|  | 61010JY00-011-G |  |  | RES,220 Ohm,+/-5%,1/16W,G,SMD0402 | YAGEO | RC0402JR-07220RL |  |  | PWA BOM |
|  | 61010JY00-044-G |  |  | RES,220 Ohm,+/-5%,1/16W,G,SMD0402 | TA-I | RM04JTN221 |  |  | PWA BOM |
| 22 | 610101V00-017-G | 0 | 40 | RES,22 Ohm,+/-5%,1/16W,G,SMD0402 | KOA SPEER ELECTRONICS, INC. | RK73B1ETTP220J | N | (+)R106,R1740,R1741,R1742,R1743,R1744,R1745,R1746,R1747,R1748,R1749,R1750,R1751,R1752,R1753,R1754,R1755,R1756,R1757,R1758,R1759,R1760,R1761,R1762,R1763,R1764,R1765,R1766,R1767,R1768,R1769,R1770,R1771,R1772,R1773,R1774,R1775,R1776,R1777,R1778 | PWA BOM |
|  | 610101V00-012-G |  |  | RES,22 Ohm,+/-5%,1/16W,G,SMD0402 | WALSIN | WR04X220JTL |  |  | PWA BOM |
|  | 610101V00-011-G |  |  | RES,22 Ohm,+/-5%,1/16W,G,SMD0402 | YAGEO | RC0402JR-0722RL |  |  | PWA BOM |
|  | 610101V00-044-G |  |  | RES,22 Ohm,+/-5%,1/16W,G,SMD0402 | TA-I | RM04JTN220 |  |  | PWA BOM |
|  | 610101V00-024-G |  |  | RES,22 Ohm,+/-5%,1/16W,G,SMD0402 | PANASONIC INDUSTRIAL CO.,LTD. | ERJ2GEJ220X |  |  | PWA BOM |
| 23 | 610115J00-017-G | 0 | 1 | RES,33 Ohm,+/-1%,1/16W,G,SMD0402 | KOA SPEER ELECTRONICS, INC. | RK73H1ETTP33R0F | N | (+)R315 | PWA BOM |
|  | 610115J00-012-G |  |  | RES,33 Ohm,+/-1%,1/16W,G,SMD0402 | WALSIN | WR04X33R0FTL |  |  | PWA BOM |
|  | 610115J00-011-G |  |  | RES,33 Ohm,+/-1%,1/16W,G,SMD0402 | YAGEO | RC0402FR-0733RL |  |  | PWA BOM |
|  | 610115J00-044-G |  |  | RES,33 Ohm,+/-1%,1/16W,G,SMD0402 | TA-I | RM04FTN33R0 |  |  | PWA BOM |
|  | 610115J00-024-G |  |  | RES,33 Ohm,+/-1%,1/16W,G,SMD0402 | PANASONIC INDUSTRIAL CO.,LTD. | ERJ2RKF33R0X |  |  | PWA BOM |
| 24 | 61100LQ00-017-G | 0 | 48 | RES,20KOhm,+/-1%,1/16W,G,SMD0402 | KOA SPEER ELECTRONICS, INC. | RN731ETTP2002F50 |  | (+)R348,R1522,R1523,R1524,R1525,R1526,R1527,R1528,R1529,R1530,R1531,R1532,R1533,R1534,R1535,R1536,R1537,R1538,R1539,R1540,R1541,R1542,R1543,R1544,R1545,R1546,R1547,R1548,R1549,R1550,R1551,R1552,R1553,R1554,R1555,R1556,R1557,R1558,R1559,R1560,R1561,R1562,R1563,R1564,R1565,R1566,R1567,R1568 | PWA BOM |
|  | 61100LQ00-012-G |  |  | RES,20KOhm,+/-1%,1/16W,G,SMD0402 | WALSIN | WF04T2002FTL |  |  | PWA BOM |
|  | 61100LQ00-011-G |  |  | RES,20KOhm,+/-1%,1/16W,G,SMD0402 | YAGEO | RT0402FRE0720KL |  |  | PWA BOM |
|  | 61100LQ00-044-G |  |  | RES,20KOhm,+/-1%,1/16W,G,SMD0402 | TA-I | RB04FTS2002 |  |  | PWA BOM |
| 25 | 610114J00-017-G | 3 | 5 | RES,2KOhm,+/-1%,1/16W,G,SMD0402 | KOA SPEER ELECTRONICS, INC. | RK73H1ETTP2001F | N | (+)R544,R545 | PWA BOM |
|  | 610114J00-012-G |  |  | RES,2KOhm,+/-1%,1/16W,G,SMD0402 | WALSIN | WR04X2001FTL |  |  | PWA BOM |
|  | 610114J00-011-G |  |  | RES,2KOhm,+/-1%,1/16W,G,SMD0402 | YAGEO | RC0402FR-072KL |  |  | PWA BOM |
|  | 610114J00-044-G |  |  | RES,2KOhm,+/-1%,1/16W,G,SMD0402 | TA-I | RM04FTN2001 |  |  | PWA BOM |
|  | 610114J00-024-G |  |  | RES,2KOhm,+/-1%,1/16W,G,SMD0402 | PANASONIC INDUSTRIAL CO.,LTD. | ERJ2RKF2001X |  |  | PWA BOM |
|  | 610114J00-029-G |  |  | RES,2KOhm,+/-1%,1/16W,G,SMD0402 | VISHAY ENTER TECHNO LOGY.INC | CRCW04022K00FKED |  |  | PWA BOM |
| 26 | 610100T00-017-G | 8 | 17 | RES,1KOhm,+/-5%,1/16W,G,SMD0402 | KOA SPEER ELECTRONICS, INC. | RK73B1ETTP102J | N | (+)R558,R561,R562,R564,R565,R566,R567,R2052,R2082 | PWA BOM |
|  | 610100T00-012-G |  |  | RES,1KOhm,+/-5%,1/16W,G,SMD0402 | WALSIN | WR04X102JTL |  |  | PWA BOM |
|  | 610100T00-011-G |  |  | RES,1KOhm,+/-5%,1/16W,G,SMD0402 | YAGEO | RC0402JR-071KL |  |  | PWA BOM |
|  | 610100T00-044-G |  |  | RES,1KOhm,+/-5%,1/16W,G,SMD0402 | TA-I | RM04JTN102 |  |  | PWA BOM |
|  | 610100T00-024-G |  |  | RES,1KOhm,+/-5%,1/16W,G,SMD0402 | PANASONIC INDUSTRIAL CO.,LTD. | ERJ2GEJ102X |  |  | PWA BOM |
| 27 | 61010L300-017-G | 2 | 10 | RES,1KOhm,+/-1%,1/16W,G,SMD0402 | KOA SPEER ELECTRONICS, INC. | RK73H1ETTP1001F | N | (+)R865,R1072,R1073,R1074,R1077,R1438,R1439,R1440 | PWA BOM |
|  | 61010L300-012-G |  |  | RES,1KOhm,+/-1%,1/16W,G,SMD0402 | WALSIN | WR04X1001FTL |  |  | PWA BOM |
|  | 61010L300-011-G |  |  | RES,1KOhm,+/-1%,1/16W,G,SMD0402 | YAGEO | RC0402FR-071KL |  |  | PWA BOM |
|  | 61010L300-044-G |  |  | RES,1KOhm,+/-1%,1/16W,G,SMD0402 | TA-I | RM04FTN1001 |  |  | PWA BOM |
|  | 61010L300-024-G |  |  | RES,1KOhm,+/-1%,1/16W,G,SMD0402 | PANASONIC INDUSTRIAL CO.,LTD. | ERJ2RKF1001X |  |  | PWA BOM |
|  | 61010L300-029-G |  |  | RES,1KOhm,+/-1%,1/16W,G,SMD0402 | VISHAY ENTER TECHNO LOGY.INC | CRCW04021K00FKED |  |  | PWA BOM |
| 28 | 61011BQ00-017-G | 1 | 2 | RES,2.2 Ohm,+/-5%,1/16W,G,SMD0402 | KOA SPEER ELECTRONICS, INC. | RK73B1ETTP2R2J | N | (+)R583 | PWA BOM |
|  | 61011BQ00-011-G |  |  | RES,2.2 Ohm,+/-5%,1/16W,G,SMD0402 | YAGEO CORPORATION COMPONENT | RC0402JR-072R2L |  |  | PWA BOM |
|  | 61011BQ00-012-G |  |  | RES,2.2 Ohm,+/-5%,1/16W,G,SMD0402 | WALSIN TECHNOLOGY CORPORATION | WR04X2R2JTL |  |  | PWA BOM |
|  | 61011BQ00-044-G |  |  | RES,2.2 Ohm,+/-5%,1/16W,G,SMD0402 | TA-I TECHNOLOGY CO., LTD | RM04JTN2R2 |  |  | PWA BOM |
| 29 | 610108300-017-G | 1 | 2 | RES,0 Ohm,+/-5%,1/10W,G,SMD0603 | KOA SPEER ELECTRONICS, INC. | RK73Z1JTTD | N | (+)R585 | PWA BOM |
|  | 610108300-012-G |  |  | RES,0 Ohm,+/-5%,1/10W,G,SMD0603 | WALSIN | WR06X000PTL |  |  | PWA BOM |
|  | 610108300-011-G |  |  | RES,0 Ohm,+/-5%,1/10W,G,SMD0603 | YAGEO | RC0603JR-070RL |  |  | PWA BOM |
|  | 610108300-044-G |  |  | RES,0 Ohm,+/-5%,1/10W,G,SMD0603 | TA-I | RM06JTN0 |  |  | PWA BOM |
|  | 610108300-024-G |  |  | RES,0 Ohm,+/-5%,1/10W,G,SMD0603 | PANASONIC INDUSTRIAL CO.,LTD. | ERJ3GEY0R00V |  |  | PWA BOM |
| 30 | 610118400-017-G | 0 | 32 | RES,27 Ohm,+/-1%,1/16W,G,SMD0402 | KOA SPEER ELECTRONICS, INC. | RK73H1ETTP27R0F | N | (+)R817,R818,R828,R830,R832,R833,R834,R860,R867,R1443,R1444,R1445,R1446,R1447,R1448,R1458,R1459,R1460,R1461,R1462,R1463,R1464,R1465,R1466,R1467,R1468,R1469,R1470,R1471,R1472,R1473,R1604 | PWA BOM |
|  | 610118400-012-G |  |  | RES,27 Ohm,+/-1%,1/16W,G,SMD0402 | WALSIN | WR04X27R0FTL |  |  | PWA BOM |
|  | 610118400-011-G |  |  | RES,27 Ohm,+/-1%,1/16W,G,SMD0402 | YAGEO | RC0402FR-0727RL |  |  | PWA BOM |
|  | 610118400-044-G |  |  | RES,27 Ohm,+/-1%,1/16W,G,SMD0402 | TA-I | RM04FTN27R0 |  |  | PWA BOM |
| 31 | 61100AH00-017-G | 1 | 36 | RES,10KOhm,+/-0.5%,1/16W,G,SMD0402 | KOA SPEER ELECTRONICS, INC. | RN731ETTP1002D25 | Y | (+)R1785,R1787,R1788,R1791,R1793,R1795,R1796,R1799,R1800,R1803,R1804,R1807,R1808,R1811,R1812,R1815,R1816,R1819,R1820,R1823,R1824,R1827,R1828,R2049,R2050,R2051,R2062,R2063,R2064,R2071,R2075,R2077,R2079,R2083,R2084 | PWA BOM |
|  | 61100AH00-012-G |  |  | RES,10KOhm,+/-0.5%,1/16W,G,SMD0402 | WALSIN | WF04U1002DTL |  |  | PWA BOM |
|  | 61100AH00-011-G |  |  | RES,10KOhm,+/-0.5%,1/16W,G,SMD0402 | YAGEO | RT0402DRE0710KL |  |  | PWA BOM |
|  | 61100AH00-044-G |  |  | RES,10KOhm,+/-0.5%,1/16W,G,SMD0402 | TA-I | RB04DTP1002 |  |  | PWA BOM |
| 32 | 61010FG00-017-G | 1 | 24 | RES,20KOhm,+/-5%,1/16W,G,SMD0402 | KOA SPEER ELECTRONICS, INC. | RK73B1ETTP203J | N | (+)R1786,R1789,R1790,R1792,R1794,R1797,R1798,R1801,R1802,R1805,R1806,R1809,R1810,R1813,R1814,R1817,R1818,R1821,R1822,R1825,R1826,R1829,R1830 | PWA BOM |
|  | 61010FG00-012-G |  |  | RES,20KOhm,+/-5%,1/16W,G,SMD0402 | WALSIN TECHNOLOGY CORPORATION | WR04X203JTL |  |  | PWA BOM |
|  | 61010FG00-011-G |  |  | RES,20KOhm,+/-5%,1/16W,G,SMD0402 | YAGEO CORPORATION COMPONENT | RC0402JR-0720KL |  |  | PWA BOM |
| 33 | 610107L00-017-G | 0 | 2 | RES,1 Ohm,+/-5%,1/10W,G,SMD0603 | KOA SPEER ELECTRONICS, INC. | RK73B1JTTD1R0J | N | (+)R1408,R1449 | PWA BOM |
| 34 | 610154800-017-G | 0 | 1 | RES,1 Ohm,+/-5%,1/8W,G,SMD0402 | KOA SPEER ELECTRONICS, INC. | SG73P1ETTP1R0J |  | (+)R2060 | PWA BOM |
| 35 | 41040B600-191-G | 0 | 1 | EEPROM,AT24C02C-SSHM-T,1.7~5.5V,2K,I2C,G,SOIC-8,SMD | ATMEL CORPORATION | AT24C02C-SSHM-T | N | (+)U_BP_FRU1 | PWA BOM |
| 36 | 21050LL00-217-G | 3 | 2 | IC,IDT,9ZXL0831AKLFT,G,VFQFPN-48,SMD | INTEGRATED DEVICE TECHNOLOGY | 9ZXL0831AKLFT |  | (+)U_Clock_B,U_Clock_A (-)U30,U31,U32 | PWA BOM |
| 37 | 31030CA00-031-G | 0 | 5 | IC,Switch,PCA9546APW,2.3~5.5V,G,TSSOP-16,SMD | NXP SEMICONDUCTORS | PCA9546APW | N | (+)U_MUX1,U_MUX2,U_MUX3,U_MUX4,U_MUX5 | PWA BOM |
|  | 31030YF00-252-G |  |  | Logic IC,Switch,PI4MSD5V9546ALEX,1.65V~5.5V,0.3ns,TSSOP,16P,G | PERICOM SEMICONDUCTOR CORP | PI4MSD5V9546ALEX |  |  | PWA BOM |
| 38 | 32040P400-399-G | 0 | 1 | IC,Voltage sensor,SLG4N020VTR,G,TDFN-8,SMD | SILEGO | SLG4N020VTR |  | (+)U_RESET | PWA BOM |
| 39 | 21081NC00-432-G | 1 | 2 | IC,LSI,500021009,A2,G,TFBGA-141,SMD | LSI LOGIC CORPORATION | 500021009 |  | (+)U_SF2 | PWA BOM |
| 40 | 310501200-183-G | 0 | 20 | IC,Buffer,SN74LVC1G07DCKR,1.65~5.5V,G,SC70-5,SMD | TEXAS INSTRUMENTS | SN74LVC1G07DCKR | N | (+)U209,U229,U230,U231,U232,U233,U234,U235,U236,U237,U238,U239,U240,U241,U242,U243,U244,U245,U246,U247 | PWA BOM |
| 41 | 220107K00-413-G | 0 | 1 | IC,PLD,10M02SCU169C8G,116MHz,3.3V,G,UBGA-169,SMD | ALTERA CORPORATION | 10M02SCU169C8G |  | (+)U248 | PWA BOM |
| 42 | 71012HD00-100-G | 0 | 1 | XTAL,25MHz,+/-20ppm,8pF,G,SMD | TXC CORPORATION | 7V25000054 |  | (+)X7 | PWA BOM |
| 43 | 71020SH00-107-G | 0 | 1 | OSC,25MHz,+/-25ppm,3.3V,15pF,G,SMD | DAISHINKU CORPORATION/DAISHINKU SINGAPORE PTE LTD/KDS | 1XSE025000AR122 |  | (+)Y3 | PWA BOM |
| 44 | 3406B0G00-309-G | 0 | 1 | CONN,Header,Pin Header,2X5,V/T,Bla,2.54mm,10u,G,SMD-10 | SAMTEC INC. | TSM-105-04-L-DV-A-P-TR |  | (+)J_CPLD_JTAG | PWA BOM |
| 45 | 9FGL0651BKILFT | 0 | 1 | IC,IDT,9FGL0651BKILFT,G,VFQFN-40,SMD | INTEGRATED DEVICE TECHNOLOGY | 9FGL0651BKILFT |  | (+)U29 | PWA BOM |
| 46 | 510301D00-223-G | 24 | 0 | MOS N,BSS138LT1G,50V,0.2A,3.5ohm@5V,G,SOT23-3,SMD | ON SEMICONDUCTOR CORP | BSS138LT1G | N | (-)Q1,Q2,Q3,Q4,Q5,Q6,Q7,Q8,Q9,Q10,Q11,Q12,Q13,Q14,Q15,Q16,Q17,Q18,Q19,Q20,Q21,Q22,Q23,Q24 | PWA BOM |
|  | 510309C00-237-G |  |  | MOS N,BSS138-7-F,50V,0.2A,3.5ohm@10V,G,SOT23-3,SMD | DIODES INCORPORATION | BSS138-7-F |  |  | PWA BOM |
|  | 510302R00-185-G |  |  | MOS N,BSS138,50V,0.22A,6ohm@4.5V,G,SOT23-3,SMD | FAIRCHILD SEMICONDUCTOR CORP | BSS138 |  |  | PWA BOM |
|  | 51030A800-221-G |  |  | MOS N,BSS138N,60V,0.23A,6ohm@4.5V,G,SOT23-3,SMD | INFINEON TECHNOLOGIES CORP. | BSS138N |  |  | PWA BOM |
| 47 | 61011H100-017-G | 14 | 0 | RES,220 Ohm,+/-1%,1/16W,G,SMD0402 | KOA SPEER ELECTRONICS, INC. | RK73H1ETTP2200F | N | (-)R870,R871,R872,R873,R922,R923,R924,R925,R926,R927,R928,R929,R930,R931 | PWA BOM |
|  | 61011H100-012-G |  |  | RES,220 Ohm,+/-1%,1/16W,G,SMD0402 | WALSIN | WR04X2200FTL |  |  | PWA BOM |
|  | 61011H100-011-G |  |  | RES,220 Ohm,+/-1%,1/16W,G,SMD0402 | YAGEO | RC0402FR-07220RL |  |  | PWA BOM |
|  | 61011H100-044-G |  |  | RES,220 Ohm,+/-1%,1/16W,G,SMD0402 | TA-I | RM04FTN2200 |  |  | PWA BOM |
|  | 61011H100-024-G |  |  | RES,220 Ohm,+/-1%,1/16W,G,SMD0402 | PANASONIC INDUSTRIAL CO.,LTD. | ERJ2RKF2200X |  |  | PWA BOM |
|  | 61011H100-029-G |  |  | RES,220 Ohm,+/-1%,1/16W,G,SMD0402 | VISHAY ENTER TECHNO LOGY.INC | CRCW0402220RFKEDC |  |  | PWA BOM |
| 48 | 41040HW00-191-G | 1 | 0 | EEPROM,AT24C02D-SSHM-T,1.7~3.6V,2K,I2C,G,SOIC-8,SMD | ATMEL CORPORATION | AT24C02D-SSHM-T |  | (-)U_BP_FRU1 | PWA BOM |
|  | 32040PJ00-223-G |  |  | IC,Temperature Sensor,NCT75DMR2G,G,MSOP-8,SMD | ON SEMICONDUCTOR CORP | NCT75DMR2G |  |  | PWA BOM |
| 49 | 310102400-183-G | 24 | 0 | IC,Gate&Inverter,SN74AHC1G32DBVR,2~5.5V,G,SOT23-5,SMD | TEXAS INSTRUMENTS | SN74AHC1G32DBVR | N | (-)U5,U6,U7,U8,U9,U10,U11,U12,U13,U14,U15,U16,U17,U18,U19,U20,U21,U22,U23,U24,U25,U26,U27,U28 | PWA BOM |
|  | 310106R00-185-G |  |  | IC,Gate&Inverter,NC7S32M5X,2~6V,G,SOT23-5,SMD | FAIRCHILD SEMICONDUCTOR CORP | NC7S32M5X |  |  | PWA BOM |
|  | 310106U00-031-G |  |  | IC,Gate&Inverter,74AHC1G32GV,2~5.5V,G,SC74A-5,SMD | NXP SEMICONDUCTORS | 74AHC1G32GV |  |  | PWA BOM |
| 50 | 21050Q500-217-G | 1 | 0 | IC,IDT,871S1022EKLFT,G,VFQFN-32,SMD | INTEGRATED DEVICE TECHNOLOGY | 871S1022EKLFT |  | (-)U29 | PWA BOM |
| 51 | 2A5910Q00-HYM-G | 8 | 0 | SMT NUT,CARBON STEEL,G,FIVETECH,82-059-01-022-01-RL | Fivetech Technology Inc. | 82-059-01-022-01-RL |  | (-)H1,H2,H3,H4,H7,H8,H9,H10 | PWA BOM |
|  | 2A5914300-G44-G |  |  | 螺母,Nut,CARBON STEEL,N/A,4.7,3.5,7,TIN Plating,圓柱,G,00 | PennEngineering Fastening | YSMTSO-47670-ET |  |  | PWA BOM |
| OOOOOOOOOOOOOOOOOOOOOOOOOOOOOOOOOOOOOOOOOOOOOOOOOOOOOOOOOOOOOOOOOOOOOOOOOOOOOOOOOOOOOOOOOO | OOOOOOOOOOOOOOOOOOOOOOOOOOOOOOOOOOOOOOOOOOOOOOOOOOOOOOOOOOOOOOOOOOOOOOOOOOOOOOOOOOOOOOOOOO | OOOOOOOOOOOOOOOOOOOOOOOOOOOOOOOOOOOOOOOOOOOOOOOOOOOOOOOOOOOOOOOOOOOOOOOOOOOOOOOOOOOOOOOOOO | OOOOOOOOOOOOOOOOOOOOOOOOOOOOOOOOOOOOOOOOOOOOOOOOOOOOOOOOOOOOOOOOOOOOOOOOOOOOOOOOOOOOOOOOOO | OOOOOOOOOOOOOOOOOOOOOOOOOOOOOOOOOOOOOOOOOOOOOOOOOOOOOOOOOOOOOOOOOOOOOOOOOOOOOOOOOOOOOOOOOO | OOOOOOOOOOOOOOOOOOOOOOOOOOOOOOOOOOOOOOOOOOOOOOOOOOOOOOOOOOOOOOOOOOOOOOOOOOOOOOOOOOOOOOOOOO | OOOOOOOOOOOOOOOOOOOOOOOOOOOOOOOOOOOOOOOOOOOOOOOOOOOOOOOOOOOOOOOOOOOOOOOOOOOOOOOOOOOOOOOOOO | OOOOOOOOOOOOOOOOOOOOOOOOOOOOOOOOOOOOOOOOOOOOOOOOOOOOOOOOOOOOOOOOOOOOOOOOOOOOOOOOOOOOOOOOOO | OOOOOOOOOOOOOOOOOOOOOOOOOOOOOOOOOOOOOOOOOOOOOOOOOOOOOOOOOOOOOOOOOOOOOOOOOOOOOOOOOOOOOOOOOO |  |
| TLA Parts Change |  |  |  |  |  |  |  |  |  |
| Item | Foxconn P/N | Qty | Part Description | Manufacturer Full Name | Manufacturer P/N | RoHS | Location | Remark |  |
| BOM Change List Date:Sat May 27 11:48:23 GMT+08:00 2017 |  |  |  |  |  |  |  |  |  |
| New BOM file : C:\<user>\Barreleye_G2-Tri-mode BPX24-EVT-X00-BOM-X02_20170517_for 2nd source.xls |  |  |  |  |  |  |  |  |  |
| Old BOM file : C:\<user>\Barreleye_G2-Tri-mode BPX24-EVT-X00-BOM-X01_20170509.xls |  |  |  |  |  |  |  |  |  |
| ##### Add Parts |  |  |  |  |  |  |  |  |  |
| Item | Location | Qty | Foxconn P/N | Part Description | Manufacturer Full Name | Manufacturer P/N | RoHS | Sheet |  |
| 1 | C2270 | 1 | 620101T02-015-G | CAP,100nF,+/-10%,X7R,16V,G,SMD0402 | MURATA ELEC. NORTH AMERICA | GRM155R71C104K | Y | PWA BOM |  |
|  |  |  | 620101T00-012-G | CAP,100nF,+/-10%,X7R,16V,G,SMD0402 | WALSIN | 0402B104K160CT |  | PWA BOM |  |
|  |  |  | 620101T00-026-G | CAP,100nF,+/-10%,X7R,16V,G,SMD0402 | SAMSUNG SEMICONDUCTOR | CL05B104KO5NNNC |  | PWA BOM |  |
|  |  |  | 620101T00-015-G | CAP,100nF,+/-10%,X7R,16V,G,SMD0402 | MURATA ELEC. NORTH AMERICA | GRM155R71C104KA88D |  | PWA BOM |  |
| 2 | OSC2 | 1 | 71020NS00-967-G | OSC,25MHz,+/-25ppm,3.3V,15pF,G,SMD | SaRonix-eCERA Corporation | FK2500025 |  | PWA BOM |  |
|  |  |  | 710209J00-100-G | OSC,25MHz,+/-25ppm,3.3V,15pF,G,SMD | TXC CORPORATION | 7X25000008 |  | PWA BOM |  |
| 3 | PSRR8,R2085,R2086 | 3 | 610107A00-017-G | RES,0 Ohm,+/-5%,1/16W,G,SMD0402 | KOA SPEER ELECTRONICS, INC. | RK73Z1ETTP | N | PWA BOM |  |
|  |  |  | 610107A00-012-G | RES,0 Ohm,+/-5%,1/16W,G,SMD0402 | WALSIN | WR04X000PTL |  | PWA BOM |  |
|  |  |  | 610107A00-011-G | RES,0 Ohm,+/-5%,1/16W,G,SMD0402 | YAGEO | RC0402JR-070RL |  | PWA BOM |  |
|  |  |  | 610107A00-044-G | RES,0 Ohm,+/-5%,1/16W,G,SMD0402 | TA-I | RM04JTN0 |  | PWA BOM |  |
|  |  |  | 610107A00-024-G | RES,0 Ohm,+/-5%,1/16W,G,SMD0402 | PANASONIC INDUSTRIAL CO.,LTD. | ERJ2GE0R00X |  | PWA BOM |  |
|  |  |  | 610107A00-029-G | RES,0 Ohm,+/-5%,1/16W,G,SMD0402 | VISHAY ENTER TECHNO LOGY.INC | CRCW04020000Z0ED |  | PWA BOM |  |
| 4 | R2148 | 1 | 61011H500-017-G | RES,22 Ohm,+/-1%,1/16W,G,SMD0402 | KOA SPEER ELECTRONICS, INC. | RK73H1ETTP22R0F | N | PWA BOM |  |
|  |  |  | 61011H500-012-G | RES,22 Ohm,+/-1%,1/16W,G,SMD0402 | WALSIN | WR04X22R0FTL |  | PWA BOM |  |
|  |  |  | 61011H500-011-G | RES,22 Ohm,+/-1%,1/16W,G,SMD0402 | YAGEO | RC0402FR-0722RL |  | PWA BOM |  |
|  |  |  | 61011H500-044-G | RES,22 Ohm,+/-1%,1/16W,G,SMD0402 | TA-I | RM04FTN22R0 |  | PWA BOM |  |
|  |  |  | 61011H500-024-G | RES,22 Ohm,+/-1%,1/16W,G,SMD0402 | PANASONIC INDUSTRIAL CO.,LTD. | ERJ2RKF22R0X |  | PWA BOM |  |
| 5 | R2128,R2129,R2130,R2131,R2132,R2133,R2134,R2135,R2136,R2137,R2138,R2139,R2140,R2141,R2142,R2143,R2144,R2145,R2146,R2147,R2149 | 21 | 610107B00-017-G | RES,4.7KOhm,+/-5%,1/16W,G,SMD0402 | KOA SPEER ELECTRONICS, INC. | RK73B1ETTP472J | N | PWA BOM |  |
|  |  |  | 610107B00-012-G | RES,4.7KOhm,+/-5%,1/16W,G,SMD0402 | WALSIN | WR04X472JTL |  | PWA BOM |  |
|  |  |  | 610107B00-011-G | RES,4.7KOhm,+/-5%,1/16W,G,SMD0402 | YAGEO | RC0402JR-074K7L |  | PWA BOM |  |
|  |  |  | 610107B00-044-G | RES,4.7KOhm,+/-5%,1/16W,G,SMD0402 | TA-I | RM04JTN472 |  | PWA BOM |  |
|  |  |  | 610107B00-024-G | RES,4.7KOhm,+/-5%,1/16W,G,SMD0402 | PANASONIC INDUSTRIAL CO.,LTD. | ERJ2GEJ472X |  | PWA BOM |  |
|  |  |  | 610107B00-029-G | RES,4.7KOhm,+/-5%,1/16W,G,SMD0402 | VISHAY ENTER TECHNO LOGY.INC | CRCW04024K70JNED |  | PWA BOM |  |
| 6 | H1,H2,H3,H4,H7,H8,H9,H10,H30,H31 | 10 | 2A5910Q00-HYM-G | SMT NUT,CARBON STEEL,G,FIVETECH,82-059-01-022-01-RL | Fivetech Technology Inc. | 82-059-01-022-01-RL |  | PWA BOM |  |
| ##### Remove Parts |  |  |  |  |  |  |  |  |  |
| Item | Location | Qty | Foxconn P/N | Part Description | Manufacturer Full Name | Manufacturer P/N | RoHS | Sheet |  |
| 1 | C2142,C2144,C2146,C2148,C2179,C2180,C2181,C2182,C2183,C2184,C2185,C2186,C2187,C2188,C2189,C2190,C2191,C2192,C2193,C2194,C2195,C2196,C2197 | 23 | 620101T02-015-G | CAP,100nF,+/-10%,X7R,16V,G,SMD0402 | MURATA ELEC. NORTH AMERICA | GRM155R71C104K | Y | PWA BOM |  |
|  |  |  | 620101T00-012-G | CAP,100nF,+/-10%,X7R,16V,G,SMD0402 | WALSIN | 0402B104K160CT |  | PWA BOM |  |
|  |  |  | 620101T00-026-G | CAP,100nF,+/-10%,X7R,16V,G,SMD0402 | SAMSUNG SEMICONDUCTOR | CL05B104KO5NNNC |  | PWA BOM |  |
|  |  |  | 620101T00-015-G | CAP,100nF,+/-10%,X7R,16V,G,SMD0402 | MURATA ELEC. NORTH AMERICA | GRM155R71C104KA88D |  | PWA BOM |  |
| 2 | C2267 | 1 | 620106200-015-G | CAP,10nF,+/-10%,X7R,16V,G,SMD0402 | MURATA ELEC. NORTH AMERICA | GRM155R71C103K | N | PWA BOM |  |
|  |  |  | 620106200-012-G | CAP,10nF,+/-10%,X7R,16V,G,SMD0402 | WALSIN | 0402B103K160CT | G | PWA BOM |  |
|  |  |  | 620106200-026-G | CAP,10nF,+/-10%,X7R,16V,G,SMD0402 | SAMSUNG | CL05B103KO5NNNC | G | PWA BOM |  |
|  |  |  | 620106200-023-G | CAP,10nF,+/-10%,X7R,16V,G,SMD0402 | TAIYO | EMK105B7103KV-F | G | PWA BOM |  |
| 3 | R1831,R1832,R1834,R1835,R1837,R1838,R1840,R1841,R1843,R1844,R1846,R1847,R1849,R1850,R1852,R1853,R1855,R1856,R1858,R1859,R1861,R1862,R1864,R1865,R1867,R1868,R1870,R1871,R1873,R1874,R1876,R1877,R1879,R1880,R1882,R1883,R1885,R1886,R2065 | 39 | 61010LA00-017-G | RES,4.7KOhm,+/-1%,1/16W,G,SMD0402 | KOA SPEER ELECTRONICS, INC. | RK73H1ETTP4701F | N | PWA BOM |  |
|  |  |  | 61010LA00-012-G | RES,4.7KOhm,+/-1%,1/16W,G,SMD0402 | WALSIN | WR04X4701FTL |  | PWA BOM |  |
|  |  |  | 61010LA00-011-G | RES,4.7KOhm,+/-1%,1/16W,G,SMD0402 | YAGEO | RC0402FR-074K7L |  | PWA BOM |  |
|  |  |  | 61010LA00-044-G | RES,4.7KOhm,+/-1%,1/16W,G,SMD0402 | TA-I | RM04FTN4701 |  | PWA BOM |  |
| 4 | R2068,R2069 | 2 | 610107A00-017-G | RES,0 Ohm,+/-5%,1/16W,G,SMD0402 | KOA SPEER ELECTRONICS, INC. | RK73Z1ETTP | N | PWA BOM |  |
|  |  |  | 610107A00-012-G | RES,0 Ohm,+/-5%,1/16W,G,SMD0402 | WALSIN | WR04X000PTL |  | PWA BOM |  |
|  |  |  | 610107A00-011-G | RES,0 Ohm,+/-5%,1/16W,G,SMD0402 | YAGEO | RC0402JR-070RL |  | PWA BOM |  |
|  |  |  | 610107A00-044-G | RES,0 Ohm,+/-5%,1/16W,G,SMD0402 | TA-I | RM04JTN0 |  | PWA BOM |  |
|  |  |  | 610107A00-024-G | RES,0 Ohm,+/-5%,1/16W,G,SMD0402 | PANASONIC INDUSTRIAL CO.,LTD. | ERJ2GE0R00X |  | PWA BOM |  |
|  |  |  | 610107A00-029-G | RES,0 Ohm,+/-5%,1/16W,G,SMD0402 | VISHAY ENTER TECHNO LOGY.INC | CRCW04020000Z0ED |  | PWA BOM |  |
| 5 | R1833,R1836,R1839,R1842,R1845,R1848,R1851,R1854,R1857,R1860,R1863,R1866,R1869,R1872,R1875,R1878,R1881,R1884,R1887 | 19 | 61011H500-017-G | RES,22 Ohm,+/-1%,1/16W,G,SMD0402 | KOA SPEER ELECTRONICS, INC. | RK73H1ETTP22R0F | N | PWA BOM |  |
|  |  |  | 61011H500-012-G | RES,22 Ohm,+/-1%,1/16W,G,SMD0402 | WALSIN | WR04X22R0FTL |  | PWA BOM |  |
|  |  |  | 61011H500-011-G | RES,22 Ohm,+/-1%,1/16W,G,SMD0402 | YAGEO | RC0402FR-0722RL |  | PWA BOM |  |
|  |  |  | 61011H500-044-G | RES,22 Ohm,+/-1%,1/16W,G,SMD0402 | TA-I | RM04FTN22R0 |  | PWA BOM |  |
|  |  |  | 61011H500-024-G | RES,22 Ohm,+/-1%,1/16W,G,SMD0402 | PANASONIC INDUSTRIAL CO.,LTD. | ERJ2RKF22R0X |  | PWA BOM |  |
| 6 | R315 | 1 | 610115J00-017-G | RES,33 Ohm,+/-1%,1/16W,G,SMD0402 | KOA SPEER ELECTRONICS, INC. | RK73H1ETTP33R0F | N | PWA BOM |  |
|  |  |  | 610115J00-012-G | RES,33 Ohm,+/-1%,1/16W,G,SMD0402 | WALSIN | WR04X33R0FTL |  | PWA BOM |  |
|  |  |  | 610115J00-011-G | RES,33 Ohm,+/-1%,1/16W,G,SMD0402 | YAGEO | RC0402FR-0733RL |  | PWA BOM |  |
|  |  |  | 610115J00-044-G | RES,33 Ohm,+/-1%,1/16W,G,SMD0402 | TA-I | RM04FTN33R0 |  | PWA BOM |  |
|  |  |  | 610115J00-024-G | RES,33 Ohm,+/-1%,1/16W,G,SMD0402 | PANASONIC INDUSTRIAL CO.,LTD. | ERJ2RKF33R0X |  | PWA BOM |  |
| 7 | R1562,R1564,R1566,R1568 | 4 | 61100LQ00-017-G | RES,20KOhm,+/-1%,1/16W,G,SMD0402 | KOA SPEER ELECTRONICS, INC. | RN731ETTP2002F50 |  | PWA BOM |  |
|  |  |  | 61100LQ00-012-G | RES,20KOhm,+/-1%,1/16W,G,SMD0402 | WALSIN | WF04T2002FTL |  | PWA BOM |  |
|  |  |  | 61100LQ00-011-G | RES,20KOhm,+/-1%,1/16W,G,SMD0402 | YAGEO | RT0402FRE0720KL |  | PWA BOM |  |
|  |  |  | 61100LQ00-044-G | RES,20KOhm,+/-1%,1/16W,G,SMD0402 | TA-I | RB04FTS2002 |  | PWA BOM |  |
| 8 | U229,U230,U231,U232,U233,U234,U235,U236,U237,U238,U239,U240,U241,U242,U243,U244,U245,U246,U247 | 19 | 310501200-183-G | IC,Buffer,SN74LVC1G07DCKR,1.65~5.5V,G,SC70-5,SMD | TEXAS INSTRUMENTS | SN74LVC1G07DCKR | N | PWA BOM |  |
| 9 | Y3 | 1 | 71020SH00-107-G | OSC,25MHz,+/-25ppm,3.3V,15pF,G,SMD | DAISHINKU CORPORATION/DAISHINKU SINGAPORE PTE LTD/KDS | 1XSE025000AR122 |  | PWA BOM |  |
| ##### Change Parts |  |  |  |  |  |  |  |  |  |
| Item | Location | Qty | Foxconn P/N | Part Description | Manufacturer Full Name | Manufacturer P/N | RoHS | Sheet | Remark |
| 1 | PSTL1,PFTL1,PETL1 | 3 | 630335M00-088-G | IND,820nH@100KHz,+/-20%,13A,8mOhm,SHLD,G,SMD | COOPER BUSSMANN, INC. | HCM0703-R82-R |  | PWA BOM | In New BOM |
|  |  |  | 63035Y800-051-G | Coil Ind,Shielded(SHLD),820nH@100KHz,+/-20%,13A,8mOhm,SMD,7.6*6.9*3.0,,,G | PULSE ELECTRONICS (SINGAPORE) | PA4341.821NLT | G | PWA BOM | In New BOM |
|  |  |  | 63032RP05-129-G | IND,820nH@100KHz,+/-20%,13A,8mOhm,SHLD,G,SMD | MAG.LAYERS, SCIENTIFIC-TECHNICS (KUNSHAN) CO., LTD. | SPS-06CZ-R82M-V1 | G | PWA BOM | In New BOM |
|  | PSTL1,PFTL1,PETL1 | 3 | 630335M00-088-G | IND,820nH@100KHz,+/-20%,13A,8mOhm,SHLD,G,SMD | COOPER BUSSMANN, INC. | HCM0703-R82-R |  | PWA BOM | In Old BOM |
|  |  |  | 63035Y800-051-G | Coil Ind,Shielded(SHLD),820nH@100KHz,+/-20%,13A,8mOhm,SMD,7.6*6.9*3.0,,,G | PULSE ELECTRONICS (SINGAPORE) | PA4341.821NLT | G | PWA BOM | In Old BOM |
|  |  |  | SPS-06CZ-R82M-V1 | Ind,SPS-06CZ-R82M-V1 | MAG.LAYERS, SCIENTIFIC-TECHNICS (KUNSHAN) CO., LTD. | SPS-06CZ-R82M-V1 | G | PWA BOM | In Old BOM |
| 2 | J_CPLD_JTAG | 1 | 15-91-2065 | CONN,Header,Pin Header,1X6,Bla,2.54mm,10u,G,SMD-6 | MOLEX INCORPORATED | 15-91-2065 |  | PWA BOM | In New BOM |
|  | J_CPLD_JTAG | 1 | 3406B0G00-309-G | CONN,Header,Pin Header,2X5,V/T,Bla,2.54mm,10u,G,SMD-10 | SAMTEC INC. | TSM-105-04-L-DV-A-P-TR |  | PWA BOM | In Old BOM |
| 3 | R875,R877,R879,R881,R883,R885,R887,R889,R891,R893,R895,R897,R899,R901,R903,R905,R907,R909,R911,R913,R915,R917,R919,R921 | 24 | 61015K700-017-G | RES,3.3 Ohm,+/-5%,1/2W,G,SMD1210 | KOA SPEER ELECTRONICS, INC. | RK73B2ETTD3R3J |  | PWA BOM | In New BOM |
|  | R875,R877,R879,R881,R883,R885,R887,R889,R891,R893,R895,R897,R899,R901,R903,R905,R907,R909,R911,R913,R915,R917,R919,R921 | 24 | 610113A00-017-G | RES,2.2 Ohm,+/-5%,1/2W,G,SMD1210 | KOA SPEER ELECTRONICS, INC. | RK73B2ETTD2R2J | N | PWA BOM | In Old BOM |
|  |  |  | 610113A00-012-G | RES,2.2 Ohm,+/-5%,1/2W,G,SMD1210 | WALSIN TECHNOLOGY CORPORATION | WF10P2R2JTL |  | PWA BOM | In Old BOM |
|  |  |  | 610113A00-011-G | RES,2.2 Ohm,+/-5%,1/2W,G,SMD1210 | YAGEO CORPORATION COMPONENT | RC1210JR-072R2L |  | PWA BOM | In Old BOM |
| 4 | U29 | 1 | 21050RJ00-217-G | IC,IDT,9FGL0651BKILFT,G,VFQFPN-40,SMD | INTEGRATED DEVICE TECHNOLOGY | 9FGL0651BKILFT |  | PWA BOM | In New BOM |
|  | U29 | 1 | 9FGL0651BKILFT | IC,IDT,9FGL0651BKILFT,G,VFQFN-40,SMD | INTEGRATED DEVICE TECHNOLOGY | 9FGL0651BKILFT |  | PWA BOM | In Old BOM |
| ##### Change Revision |  |  |  |  |  |  |  |  |  |
| Sheet | REV OF BOM | CUSTOMER | CUSTOMER P/N | PWA PN | PWA DESCRIPTION | PWA REV | DATE | Remark |  |
| OOOOOOOOOOOOOOOOOOOOOOOOOOOOOOOOOOOOOOOOOOOOOOOOOOOOOOOOOOOOOOOOOOOOOOOOOOOOOOOOOOOOOOOOOO | OOOOOOOOOOOOOOOOOOOOOOOOOOOOOOOOOOOOOOOOOOOOOOOOOOOOOOOOOOOOOOOOOOOOOOOOOOOOOOOOOOOOOOOOOO | OOOOOOOOOOOOOOOOOOOOOOOOOOOOOOOOOOOOOOOOOOOOOOOOOOOOOOOOOOOOOOOOOOOOOOOOOOOOOOOOOOOOOOOOOO | OOOOOOOOOOOOOOOOOOOOOOOOOOOOOOOOOOOOOOOOOOOOOOOOOOOOOOOOOOOOOOOOOOOOOOOOOOOOOOOOOOOOOOOOOO | OOOOOOOOOOOOOOOOOOOOOOOOOOOOOOOOOOOOOOOOOOOOOOOOOOOOOOOOOOOOOOOOOOOOOOOOOOOOOOOOOOOOOOOOOO | OOOOOOOOOOOOOOOOOOOOOOOOOOOOOOOOOOOOOOOOOOOOOOOOOOOOOOOOOOOOOOOOOOOOOOOOOOOOOOOOOOOOOOOOOO | OOOOOOOOOOOOOOOOOOOOOOOOOOOOOOOOOOOOOOOOOOOOOOOOOOOOOOOOOOOOOOOOOOOOOOOOOOOOOOOOOOOOOOOOOO | OOOOOOOOOOOOOOOOOOOOOOOOOOOOOOOOOOOOOOOOOOOOOOOOOOOOOOOOOOOOOOOOOOOOOOOOOOOOOOOOOOOOOOOOOO | OOOOOOOOOOOOOOOOOOOOOOOOOOOOOOOOOOOOOOOOOOOOOOOOOOOOOOOOOOOOOOOOOOOOOOOOOOOOOOOOOOOOOOOOOO | OOOOOOOOOOOOOOOOOOOOOOOOOOOOOOOOOOOOOOOOOOOOOOOOOOOOOOOOOOOOOOOOOOOOOOOOOOOOOOOOOOOOOOOOOO |
| Second Source Change |  |  |  |  |  |  |  |  |  |
| Item | Location | Change Type | Foxconn P/N | Part Description | Manufacturer Full Name | Manufacturer P/N | RoHS | Sheet |  |
| 1 | PSTL1,PFTL1,PETL1 |  | 630335M00-088-G | IND,820nH@100KHz,+/-20%,13A,8mOhm,SHLD,G,SMD | COOPER BUSSMANN, INC. | HCM0703-R82-R |  | PWA BOM |  |
|  |  | NO | 63035Y800-051-G | Coil Ind,Shielded(SHLD),820nH@100KHz,+/-20%,13A,8mOhm,SMD,7.6*6.9*3.0,,,G | PULSE ELECTRONICS (SINGAPORE) | PA4341.821NLT | G | PWA BOM |  |
|  |  | ADD | 63032RP05-129-G | IND,820nH@100KHz,+/-20%,13A,8mOhm,SHLD,G,SMD | MAG.LAYERS, SCIENTIFIC-TECHNICS (KUNSHAN) CO., LTD. | SPS-06CZ-R82M-V1 | G | PWA BOM |  |
|  |  | Delete | SPS-06CZ-R82M-V1 | Ind,SPS-06CZ-R82M-V1 | MAG.LAYERS, SCIENTIFIC-TECHNICS (KUNSHAN) CO., LTD. | SPS-06CZ-R82M-V1 | G | PWA BOM |  |
| OOOOOOOOOOOOOOOOOOOOOOOOOOOOOOOOOOOOOOOOOOOOOOOOOOOOOOOOOOOOOOOOOOOOOOOOOOOOOOOOOOOOOOOOOO | OOOOOOOOOOOOOOOOOOOOOOOOOOOOOOOOOOOOOOOOOOOOOOOOOOOOOOOOOOOOOOOOOOOOOOOOOOOOOOOOOOOOOOOOOO | OOOOOOOOOOOOOOOOOOOOOOOOOOOOOOOOOOOOOOOOOOOOOOOOOOOOOOOOOOOOOOOOOOOOOOOOOOOOOOOOOOOOOOOOOO | OOOOOOOOOOOOOOOOOOOOOOOOOOOOOOOOOOOOOOOOOOOOOOOOOOOOOOOOOOOOOOOOOOOOOOOOOOOOOOOOOOOOOOOOOO | OOOOOOOOOOOOOOOOOOOOOOOOOOOOOOOOOOOOOOOOOOOOOOOOOOOOOOOOOOOOOOOOOOOOOOOOOOOOOOOOOOOOOOOOOO | OOOOOOOOOOOOOOOOOOOOOOOOOOOOOOOOOOOOOOOOOOOOOOOOOOOOOOOOOOOOOOOOOOOOOOOOOOOOOOOOOOOOOOOOOO | OOOOOOOOOOOOOOOOOOOOOOOOOOOOOOOOOOOOOOOOOOOOOOOOOOOOOOOOOOOOOOOOOOOOOOOOOOOOOOOOOOOOOOOOOO | OOOOOOOOOOOOOOOOOOOOOOOOOOOOOOOOOOOOOOOOOOOOOOOOOOOOOOOOOOOOOOOOOOOOOOOOOOOOOOOOOOOOOOOOOO | OOOOOOOOOOOOOOOOOOOOOOOOOOOOOOOOOOOOOOOOOOOOOOOOOOOOOOOOOOOOOOOOOOOOOOOOOOOOOOOOOOOOOOOOOO | OOOOOOOOOOOOOOOOOOOOOOOOOOOOOOOOOOOOOOOOOOOOOOOOOOOOOOOOOOOOOOOOOOOOOOOOOOOOOOOOOOOOOOOOOO |
| Master Materials Change |  |  |  |  |  |  |  |  |  |
| Item | Foxconn P/N | Orig._Usage | New_Usage | Part Description | Manufacturer Full Name | Manufacturer P/N | RoHS | Location | Sheet |
| 1 | 620101T02-015-G | 164 | 142 | CAP,100nF,+/-10%,X7R,16V,G,SMD0402 | MURATA ELEC. NORTH AMERICA | GRM155R71C104K | Y | (+)C2270 (-)C2142,C2144,C2146,C2148,C2179,C2180,C2181,C2182,C2183,C2184,C2185,C2186,C2187,C2188,C2189,C2190,C2191,C2192,C2193,C2194,C2195,C2196,C2197 | PWA BOM |
|  | 620101T00-012-G |  |  | CAP,100nF,+/-10%,X7R,16V,G,SMD0402 | WALSIN | 0402B104K160CT |  |  | PWA BOM |
|  | 620101T00-026-G |  |  | CAP,100nF,+/-10%,X7R,16V,G,SMD0402 | SAMSUNG SEMICONDUCTOR | CL05B104KO5NNNC |  |  | PWA BOM |
|  | 620101T00-015-G |  |  | CAP,100nF,+/-10%,X7R,16V,G,SMD0402 | MURATA ELEC. NORTH AMERICA | GRM155R71C104KA88D |  |  | PWA BOM |
| 2 | 15-91-2065 | 0 | 1 | CONN,Header,Pin Header,1X6,Bla,2.54mm,10u,G,SMD-6 | MOLEX INCORPORATED | 15-91-2065 |  | (+)J_CPLD_JTAG | PWA BOM |
| 3 | 71020NS00-967-G | 1 | 2 | OSC,25MHz,+/-25ppm,3.3V,15pF,G,SMD | SaRonix-eCERA Corporation | FK2500025 |  | (+)OSC2 | PWA BOM |
|  | 710209J00-100-G |  |  | OSC,25MHz,+/-25ppm,3.3V,15pF,G,SMD | TXC CORPORATION | 7X25000008 |  |  | PWA BOM |
| 4 | 61010LA00-017-G | 84 | 45 | RES,4.7KOhm,+/-1%,1/16W,G,SMD0402 | KOA SPEER ELECTRONICS, INC. | RK73H1ETTP4701F | N | (-)R1831,R1832,R1834,R1835,R1837,R1838,R1840,R1841,R1843,R1844,R1846,R1847,R1849,R1850,R1852,R1853,R1855,R1856,R1858,R1859,R1861,R1862,R1864,R1865,R1867,R1868,R1870,R1871,R1873,R1874,R1876,R1877,R1879,R1880,R1882,R1883,R1885,R1886,R2065 | PWA BOM |
|  | 61010LA00-012-G |  |  | RES,4.7KOhm,+/-1%,1/16W,G,SMD0402 | WALSIN | WR04X4701FTL |  |  | PWA BOM |
|  | 61010LA00-011-G |  |  | RES,4.7KOhm,+/-1%,1/16W,G,SMD0402 | YAGEO | RC0402FR-074K7L |  |  | PWA BOM |
|  | 61010LA00-044-G |  |  | RES,4.7KOhm,+/-1%,1/16W,G,SMD0402 | TA-I | RM04FTN4701 |  |  | PWA BOM |
| 5 | 610107A00-017-G | 120 | 121 | RES,0 Ohm,+/-5%,1/16W,G,SMD0402 | KOA SPEER ELECTRONICS, INC. | RK73Z1ETTP | N | (+)PSRR8,R2085,R2086 (-)R2068,R2069 | PWA BOM |
|  | 610107A00-012-G |  |  | RES,0 Ohm,+/-5%,1/16W,G,SMD0402 | WALSIN | WR04X000PTL |  |  | PWA BOM |
|  | 610107A00-011-G |  |  | RES,0 Ohm,+/-5%,1/16W,G,SMD0402 | YAGEO | RC0402JR-070RL |  |  | PWA BOM |
|  | 610107A00-044-G |  |  | RES,0 Ohm,+/-5%,1/16W,G,SMD0402 | TA-I | RM04JTN0 |  |  | PWA BOM |
|  | 610107A00-024-G |  |  | RES,0 Ohm,+/-5%,1/16W,G,SMD0402 | PANASONIC INDUSTRIAL CO.,LTD. | ERJ2GE0R00X |  |  | PWA BOM |
|  | 610107A00-029-G |  |  | RES,0 Ohm,+/-5%,1/16W,G,SMD0402 | VISHAY ENTER TECHNO LOGY.INC | CRCW04020000Z0ED |  |  | PWA BOM |
| 6 | 61011H500-017-G | 30 | 12 | RES,22 Ohm,+/-1%,1/16W,G,SMD0402 | KOA SPEER ELECTRONICS, INC. | RK73H1ETTP22R0F | N | (+)R2148 (-)R1833,R1836,R1839,R1842,R1845,R1848,R1851,R1854,R1857,R1860,R1863,R1866,R1869,R1872,R1875,R1878,R1881,R1884,R1887 | PWA BOM |
|  | 61011H500-012-G |  |  | RES,22 Ohm,+/-1%,1/16W,G,SMD0402 | WALSIN | WR04X22R0FTL |  |  | PWA BOM |
|  | 61011H500-011-G |  |  | RES,22 Ohm,+/-1%,1/16W,G,SMD0402 | YAGEO | RC0402FR-0722RL |  |  | PWA BOM |
|  | 61011H500-044-G |  |  | RES,22 Ohm,+/-1%,1/16W,G,SMD0402 | TA-I | RM04FTN22R0 |  |  | PWA BOM |
|  | 61011H500-024-G |  |  | RES,22 Ohm,+/-1%,1/16W,G,SMD0402 | PANASONIC INDUSTRIAL CO.,LTD. | ERJ2RKF22R0X |  |  | PWA BOM |
| 7 | 610107B00-017-G | 152 | 173 | RES,4.7KOhm,+/-5%,1/16W,G,SMD0402 | KOA SPEER ELECTRONICS, INC. | RK73B1ETTP472J | N | (+)R2128,R2129,R2130,R2131,R2132,R2133,R2134,R2135,R2136,R2137,R2138,R2139,R2140,R2141,R2142,R2143,R2144,R2145,R2146,R2147,R2149 | PWA BOM |
|  | 610107B00-012-G |  |  | RES,4.7KOhm,+/-5%,1/16W,G,SMD0402 | WALSIN | WR04X472JTL |  |  | PWA BOM |
|  | 610107B00-011-G |  |  | RES,4.7KOhm,+/-5%,1/16W,G,SMD0402 | YAGEO | RC0402JR-074K7L |  |  | PWA BOM |
|  | 610107B00-044-G |  |  | RES,4.7KOhm,+/-5%,1/16W,G,SMD0402 | TA-I | RM04JTN472 |  |  | PWA BOM |
|  | 610107B00-024-G |  |  | RES,4.7KOhm,+/-5%,1/16W,G,SMD0402 | PANASONIC INDUSTRIAL CO.,LTD. | ERJ2GEJ472X |  |  | PWA BOM |
|  | 610107B00-029-G |  |  | RES,4.7KOhm,+/-5%,1/16W,G,SMD0402 | VISHAY ENTER TECHNO LOGY.INC | CRCW04024K70JNED |  |  | PWA BOM |
| 8 | 61100LQ00-017-G | 48 | 44 | RES,20KOhm,+/-1%,1/16W,G,SMD0402 | KOA SPEER ELECTRONICS, INC. | RN731ETTP2002F50 |  | (-)R1562,R1564,R1566,R1568 | PWA BOM |
|  | 61100LQ00-012-G |  |  | RES,20KOhm,+/-1%,1/16W,G,SMD0402 | WALSIN | WF04T2002FTL |  |  | PWA BOM |
|  | 61100LQ00-011-G |  |  | RES,20KOhm,+/-1%,1/16W,G,SMD0402 | YAGEO | RT0402FRE0720KL |  |  | PWA BOM |
|  | 61100LQ00-044-G |  |  | RES,20KOhm,+/-1%,1/16W,G,SMD0402 | TA-I | RB04FTS2002 |  |  | PWA BOM |
| 9 | 610113A00-017-G | 48 | 24 | RES,2.2 Ohm,+/-5%,1/2W,G,SMD1210 | KOA SPEER ELECTRONICS, INC. | RK73B2ETTD2R2J | N | (-)R875,R877,R879,R881,R883,R885,R887,R889,R891,R893,R895,R897,R899,R901,R903,R905,R907,R909,R911,R913,R915,R917,R919,R921 | PWA BOM |
|  | 610113A00-012-G |  |  | RES,2.2 Ohm,+/-5%,1/2W,G,SMD1210 | WALSIN TECHNOLOGY CORPORATION | WF10P2R2JTL |  |  | PWA BOM |
|  | 610113A00-011-G |  |  | RES,2.2 Ohm,+/-5%,1/2W,G,SMD1210 | YAGEO CORPORATION COMPONENT | RC1210JR-072R2L |  |  | PWA BOM |
| 10 | 61015K700-017-G | 0 | 24 | RES,3.3 Ohm,+/-5%,1/2W,G,SMD1210 | KOA SPEER ELECTRONICS, INC. | RK73B2ETTD3R3J |  | (+)R875,R877,R879,R881,R883,R885,R887,R889,R891,R893,R895,R897,R899,R901,R903,R905,R907,R909,R911,R913,R915,R917,R919,R921 | PWA BOM |
| 11 | 21050RJ00-217-G | 0 | 1 | IC,IDT,9FGL0651BKILFT,G,VFQFPN-40,SMD | INTEGRATED DEVICE TECHNOLOGY | 9FGL0651BKILFT |  | (+)U29 | PWA BOM |
| 12 | 310501200-183-G | 20 | 1 | IC,Buffer,SN74LVC1G07DCKR,1.65~5.5V,G,SC70-5,SMD | TEXAS INSTRUMENTS | SN74LVC1G07DCKR | N | (-)U229,U230,U231,U232,U233,U234,U235,U236,U237,U238,U239,U240,U241,U242,U243,U244,U245,U246,U247 | PWA BOM |
| 13 | 2A5910Q00-HYM-G | 0 | 10 | SMT NUT,CARBON STEEL,G,FIVETECH,82-059-01-022-01-RL | Fivetech Technology Inc. | 82-059-01-022-01-RL |  | (+)H1,H2,H3,H4,H7,H8,H9,H10,H30,H31 | PWA BOM |
| 14 | 620106200-015-G | 1 | 0 | CAP,10nF,+/-10%,X7R,16V,G,SMD0402 | MURATA ELEC. NORTH AMERICA | GRM155R71C103K | N | (-)C2267 | PWA BOM |
|  | 620106200-012-G |  |  | CAP,10nF,+/-10%,X7R,16V,G,SMD0402 | WALSIN | 0402B103K160CT |  |  | PWA BOM |
|  | 620106200-026-G |  |  | CAP,10nF,+/-10%,X7R,16V,G,SMD0402 | SAMSUNG | CL05B103KO5NNNC |  |  | PWA BOM |
|  | 620106200-023-G |  |  | CAP,10nF,+/-10%,X7R,16V,G,SMD0402 | TAIYO | EMK105B7103KV-F |  |  | PWA BOM |
| 15 | 610115J00-017-G | 1 | 0 | RES,33 Ohm,+/-1%,1/16W,G,SMD0402 | KOA SPEER ELECTRONICS, INC. | RK73H1ETTP33R0F | N | (-)R315 | PWA BOM |
|  | 610115J00-012-G |  |  | RES,33 Ohm,+/-1%,1/16W,G,SMD0402 | WALSIN | WR04X33R0FTL |  |  | PWA BOM |
|  | 610115J00-011-G |  |  | RES,33 Ohm,+/-1%,1/16W,G,SMD0402 | YAGEO | RC0402FR-0733RL |  |  | PWA BOM |
|  | 610115J00-044-G |  |  | RES,33 Ohm,+/-1%,1/16W,G,SMD0402 | TA-I | RM04FTN33R0 |  |  | PWA BOM |
|  | 610115J00-024-G |  |  | RES,33 Ohm,+/-1%,1/16W,G,SMD0402 | PANASONIC INDUSTRIAL CO.,LTD. | ERJ2RKF33R0X |  |  | PWA BOM |
| 16 | 71020SH00-107-G | 1 | 0 | OSC,25MHz,+/-25ppm,3.3V,15pF,G,SMD | DAISHINKU CORPORATION/DAISHINKU SINGAPORE PTE LTD/KDS | 1XSE025000AR122 |  | (-)Y3 | PWA BOM |
| 17 | 3406B0G00-309-G | 1 | 0 | CONN,Header,Pin Header,2X5,V/T,Bla,2.54mm,10u,G,SMD-10 | SAMTEC INC. | TSM-105-04-L-DV-A-P-TR |  | (-)J_CPLD_JTAG | PWA BOM |
| 18 | 9FGL0651BKILFT | 1 | 0 | IC,IDT,9FGL0651BKILFT,G,VFQFN-40,SMD | INTEGRATED DEVICE TECHNOLOGY | 9FGL0651BKILFT |  | (-)U29 | PWA BOM |
| OOOOOOOOOOOOOOOOOOOOOOOOOOOOOOOOOOOOOOOOOOOOOOOOOOOOOOOOOOOOOOOOOOOOOOOOOOOOOOOOOOOOOOOOOO | OOOOOOOOOOOOOOOOOOOOOOOOOOOOOOOOOOOOOOOOOOOOOOOOOOOOOOOOOOOOOOOOOOOOOOOOOOOOOOOOOOOOOOOOOO | OOOOOOOOOOOOOOOOOOOOOOOOOOOOOOOOOOOOOOOOOOOOOOOOOOOOOOOOOOOOOOOOOOOOOOOOOOOOOOOOOOOOOOOOOO | OOOOOOOOOOOOOOOOOOOOOOOOOOOOOOOOOOOOOOOOOOOOOOOOOOOOOOOOOOOOOOOOOOOOOOOOOOOOOOOOOOOOOOOOOO | OOOOOOOOOOOOOOOOOOOOOOOOOOOOOOOOOOOOOOOOOOOOOOOOOOOOOOOOOOOOOOOOOOOOOOOOOOOOOOOOOOOOOOOOOO | OOOOOOOOOOOOOOOOOOOOOOOOOOOOOOOOOOOOOOOOOOOOOOOOOOOOOOOOOOOOOOOOOOOOOOOOOOOOOOOOOOOOOOOOOO | OOOOOOOOOOOOOOOOOOOOOOOOOOOOOOOOOOOOOOOOOOOOOOOOOOOOOOOOOOOOOOOOOOOOOOOOOOOOOOOOOOOOOOOOOO | OOOOOOOOOOOOOOOOOOOOOOOOOOOOOOOOOOOOOOOOOOOOOOOOOOOOOOOOOOOOOOOOOOOOOOOOOOOOOOOOOOOOOOOOOO | OOOOOOOOOOOOOOOOOOOOOOOOOOOOOOOOOOOOOOOOOOOOOOOOOOOOOOOOOOOOOOOOOOOOOOOOOOOOOOOOOOOOOOOOOO |  |
| TLA Parts Change |  |  |  |  |  |  |  |  |  |
| Item | Foxconn P/N | Qty | Part Description | Manufacturer Full Name | Manufacturer P/N | RoHS | Location | Remark |  |
| 1 | 1B51GF500-600-G | 1 | 8_MYLAR_HDD_BP_FRONT_POWER9 | 1B51GF500-600-G | 1B51GF500-600-G | G |  | In New BOM |  |
| BOM Change List Date:Sat May 27 11:49:03 GMT+08:00 2017 |  |  |  |  |  |  |  |  |  |
| New BOM file : C:\<user>\Barreleye_G2-Tri-mode BPX24-EVT-X00-BOM-X03_20170526.xls |  |  |  |  |  |  |  |  |  |
| Old BOM file : C:\<user>\Barreleye_G2-Tri-mode BPX24-EVT-X00-BOM-X02_20170517_for 2nd source.xls |  |  |  |  |  |  |  |  |  |
| ##### Add Parts |  |  |  |  |  |  |  |  |  |
| Item | Location | Qty | Foxconn P/N | Part Description | Manufacturer Full Name | Manufacturer P/N | RoHS | Sheet |  |
| 1 | C397 | 1 | 620101T02-015-G | CAP,100nF,+/-10%,X7R,16V,G,SMD0402 | MURATA ELEC. NORTH AMERICA | GRM155R71C104K | Y | PWA BOM |  |
|  |  |  | 620101T00-012-G | CAP,100nF,+/-10%,X7R,16V,G,SMD0402 | WALSIN | 0402B104K160CT |  | PWA BOM |  |
|  |  |  | 620101T00-026-G | CAP,100nF,+/-10%,X7R,16V,G,SMD0402 | SAMSUNG SEMICONDUCTOR | CL05B104KO5NNNC |  | PWA BOM |  |
|  |  |  | 620101T00-015-G | CAP,100nF,+/-10%,X7R,16V,G,SMD0402 | MURATA ELEC. NORTH AMERICA | GRM155R71C104KA88D |  | PWA BOM |  |
| 2 | R229,R230,R251,R252 | 4 | 61010LA00-017-G | RES,4.7KOhm,+/-1%,1/16W,G,SMD0402 | KOA SPEER ELECTRONICS, INC. | RK73H1ETTP4701F | N | PWA BOM |  |
|  |  |  | 61010LA00-012-G | RES,4.7KOhm,+/-1%,1/16W,G,SMD0402 | WALSIN | WR04X4701FTL |  | PWA BOM |  |
|  |  |  | 61010LA00-011-G | RES,4.7KOhm,+/-1%,1/16W,G,SMD0402 | YAGEO | RC0402FR-074K7L |  | PWA BOM |  |
|  |  |  | 61010LA00-044-G | RES,4.7KOhm,+/-1%,1/16W,G,SMD0402 | TA-I | RM04FTN4701 |  | PWA BOM |  |
| 3 | R228 | 1 | 610107B00-017-G | RES,4.7KOhm,+/-5%,1/16W,G,SMD0402 | KOA SPEER ELECTRONICS, INC. | RK73B1ETTP472J | N | PWA BOM |  |
|  |  |  | 610107B00-012-G | RES,4.7KOhm,+/-5%,1/16W,G,SMD0402 | WALSIN | WR04X472JTL |  | PWA BOM |  |
|  |  |  | 610107B00-011-G | RES,4.7KOhm,+/-5%,1/16W,G,SMD0402 | YAGEO | RC0402JR-074K7L |  | PWA BOM |  |
|  |  |  | 610107B00-044-G | RES,4.7KOhm,+/-5%,1/16W,G,SMD0402 | TA-I | RM04JTN472 |  | PWA BOM |  |
|  |  |  | 610107B00-024-G | RES,4.7KOhm,+/-5%,1/16W,G,SMD0402 | PANASONIC INDUSTRIAL CO.,LTD. | ERJ2GEJ472X |  | PWA BOM |  |
|  |  |  | 610107B00-029-G | RES,4.7KOhm,+/-5%,1/16W,G,SMD0402 | VISHAY ENTER TECHNO LOGY.INC | CRCW04024K70JNED |  | PWA BOM |  |
| 4 | U_I2C_RE2 | 1 | 311004800-031-G | IC,Translator,PCA9617ADPJ,0.8~5.5V,2.2~5.5V,G,TSSOP-8,SMD | NXP SEMICONDUCTORS | PCA9617ADPJ |  | PWA BOM |  |
|  |  |  | 311004V00-223-G | Logic IC,Translator,PCA9617ADMR2G,Vcca=0.8V~5.5V,Vccb=2.2V~5.5V,102ns,Micro8,8P,G | ON SEMICONDUCTOR CORP | PCA9617ADMR2G |  | PWA BOM |  |
| ##### Remove Parts |  |  |  |  |  |  |  |  |  |
| Item | Location | Qty | Foxconn P/N | Part Description | Manufacturer Full Name | Manufacturer P/N | RoHS | Sheet |  |
| ##### Change Parts |  |  |  |  |  |  |  |  |  |
| Item | Location | Qty | Foxconn P/N | Part Description | Manufacturer Full Name | Manufacturer P/N | RoHS | Sheet | Remark |
| 1 | J_CPLD_JTAG | 1 | 3406B6F00-317-G | CONN,Header,WTB,2X3,R/A,Bla,2.5mm,15u,G,SMD-6 | MOLEX INCORPORATED | 15-91-2065 |  | PWA BOM | In New BOM |
|  | J_CPLD_JTAG | 1 | 15-91-2065 | CONN,Header,Pin Header,1X6,Bla,2.54mm,10u,G,SMD-6 | MOLEX INCORPORATED | 15-91-2065 |  | PWA BOM | In Old BOM |
| ##### Change Revision |  |  |  |  |  |  |  |  |  |
| Sheet | REV OF BOM | CUSTOMER | CUSTOMER P/N | PWA PN | PWA DESCRIPTION | PWA REV | DATE | Remark |  |
| OOOOOOOOOOOOOOOOOOOOOOOOOOOOOOOOOOOOOOOOOOOOOOOOOOOOOOOOOOOOOOOOOOOOOOOOOOOOOOOOOOOOOOOOOO | OOOOOOOOOOOOOOOOOOOOOOOOOOOOOOOOOOOOOOOOOOOOOOOOOOOOOOOOOOOOOOOOOOOOOOOOOOOOOOOOOOOOOOOOOO | OOOOOOOOOOOOOOOOOOOOOOOOOOOOOOOOOOOOOOOOOOOOOOOOOOOOOOOOOOOOOOOOOOOOOOOOOOOOOOOOOOOOOOOOOO | OOOOOOOOOOOOOOOOOOOOOOOOOOOOOOOOOOOOOOOOOOOOOOOOOOOOOOOOOOOOOOOOOOOOOOOOOOOOOOOOOOOOOOOOOO | OOOOOOOOOOOOOOOOOOOOOOOOOOOOOOOOOOOOOOOOOOOOOOOOOOOOOOOOOOOOOOOOOOOOOOOOOOOOOOOOOOOOOOOOOO | OOOOOOOOOOOOOOOOOOOOOOOOOOOOOOOOOOOOOOOOOOOOOOOOOOOOOOOOOOOOOOOOOOOOOOOOOOOOOOOOOOOOOOOOOO | OOOOOOOOOOOOOOOOOOOOOOOOOOOOOOOOOOOOOOOOOOOOOOOOOOOOOOOOOOOOOOOOOOOOOOOOOOOOOOOOOOOOOOOOOO | OOOOOOOOOOOOOOOOOOOOOOOOOOOOOOOOOOOOOOOOOOOOOOOOOOOOOOOOOOOOOOOOOOOOOOOOOOOOOOOOOOOOOOOOOO | OOOOOOOOOOOOOOOOOOOOOOOOOOOOOOOOOOOOOOOOOOOOOOOOOOOOOOOOOOOOOOOOOOOOOOOOOOOOOOOOOOOOOOOOOO | OOOOOOOOOOOOOOOOOOOOOOOOOOOOOOOOOOOOOOOOOOOOOOOOOOOOOOOOOOOOOOOOOOOOOOOOOOOOOOOOOOOOOOOOOO |
| Second Source Change |  |  |  |  |  |  |  |  |  |
| Item | Location | Change Type | Foxconn P/N | Part Description | Manufacturer Full Name | Manufacturer P/N | RoHS | Sheet |  |
| OOOOOOOOOOOOOOOOOOOOOOOOOOOOOOOOOOOOOOOOOOOOOOOOOOOOOOOOOOOOOOOOOOOOOOOOOOOOOOOOOOOOOOOOOO | OOOOOOOOOOOOOOOOOOOOOOOOOOOOOOOOOOOOOOOOOOOOOOOOOOOOOOOOOOOOOOOOOOOOOOOOOOOOOOOOOOOOOOOOOO | OOOOOOOOOOOOOOOOOOOOOOOOOOOOOOOOOOOOOOOOOOOOOOOOOOOOOOOOOOOOOOOOOOOOOOOOOOOOOOOOOOOOOOOOOO | OOOOOOOOOOOOOOOOOOOOOOOOOOOOOOOOOOOOOOOOOOOOOOOOOOOOOOOOOOOOOOOOOOOOOOOOOOOOOOOOOOOOOOOOOO | OOOOOOOOOOOOOOOOOOOOOOOOOOOOOOOOOOOOOOOOOOOOOOOOOOOOOOOOOOOOOOOOOOOOOOOOOOOOOOOOOOOOOOOOOO | OOOOOOOOOOOOOOOOOOOOOOOOOOOOOOOOOOOOOOOOOOOOOOOOOOOOOOOOOOOOOOOOOOOOOOOOOOOOOOOOOOOOOOOOOO | OOOOOOOOOOOOOOOOOOOOOOOOOOOOOOOOOOOOOOOOOOOOOOOOOOOOOOOOOOOOOOOOOOOOOOOOOOOOOOOOOOOOOOOOOO | OOOOOOOOOOOOOOOOOOOOOOOOOOOOOOOOOOOOOOOOOOOOOOOOOOOOOOOOOOOOOOOOOOOOOOOOOOOOOOOOOOOOOOOOOO | OOOOOOOOOOOOOOOOOOOOOOOOOOOOOOOOOOOOOOOOOOOOOOOOOOOOOOOOOOOOOOOOOOOOOOOOOOOOOOOOOOOOOOOOOO | OOOOOOOOOOOOOOOOOOOOOOOOOOOOOOOOOOOOOOOOOOOOOOOOOOOOOOOOOOOOOOOOOOOOOOOOOOOOOOOOOOOOOOOOOO |
| Master Materials Change |  |  |  |  |  |  |  |  |  |
| Item | Foxconn P/N | Orig._Usage | New_Usage | Part Description | Manufacturer Full Name | Manufacturer P/N | RoHS | Location | Sheet |
| 1 | 620101T02-015-G | 142 | 143 | CAP,100nF,+/-10%,X7R,16V,G,SMD0402 | MURATA ELEC. NORTH AMERICA | GRM155R71C104K | Y | (+)C397 | PWA BOM |
|  | 620101T00-012-G |  |  | CAP,100nF,+/-10%,X7R,16V,G,SMD0402 | WALSIN | 0402B104K160CT |  |  | PWA BOM |
|  | 620101T00-026-G |  |  | CAP,100nF,+/-10%,X7R,16V,G,SMD0402 | SAMSUNG SEMICONDUCTOR | CL05B104KO5NNNC |  |  | PWA BOM |
|  | 620101T00-015-G |  |  | CAP,100nF,+/-10%,X7R,16V,G,SMD0402 | MURATA ELEC. NORTH AMERICA | GRM155R71C104KA88D |  |  | PWA BOM |
| 2 | 61010LA00-017-G | 45 | 49 | RES,4.7KOhm,+/-1%,1/16W,G,SMD0402 | KOA SPEER ELECTRONICS, INC. | RK73H1ETTP4701F | N | (+)R229,R230,R251,R252 | PWA BOM |
|  | 61010LA00-012-G |  |  | RES,4.7KOhm,+/-1%,1/16W,G,SMD0402 | WALSIN | WR04X4701FTL |  |  | PWA BOM |
|  | 61010LA00-011-G |  |  | RES,4.7KOhm,+/-1%,1/16W,G,SMD0402 | YAGEO | RC0402FR-074K7L |  |  | PWA BOM |
|  | 61010LA00-044-G |  |  | RES,4.7KOhm,+/-1%,1/16W,G,SMD0402 | TA-I | RM04FTN4701 |  |  | PWA BOM |
| 3 | 610107B00-017-G | 173 | 174 | RES,4.7KOhm,+/-5%,1/16W,G,SMD0402 | KOA SPEER ELECTRONICS, INC. | RK73B1ETTP472J | N | (+)R228 | PWA BOM |
|  | 610107B00-012-G |  |  | RES,4.7KOhm,+/-5%,1/16W,G,SMD0402 | WALSIN | WR04X472JTL |  |  | PWA BOM |
|  | 610107B00-011-G |  |  | RES,4.7KOhm,+/-5%,1/16W,G,SMD0402 | YAGEO | RC0402JR-074K7L |  |  | PWA BOM |
|  | 610107B00-044-G |  |  | RES,4.7KOhm,+/-5%,1/16W,G,SMD0402 | TA-I | RM04JTN472 |  |  | PWA BOM |
|  | 610107B00-024-G |  |  | RES,4.7KOhm,+/-5%,1/16W,G,SMD0402 | PANASONIC INDUSTRIAL CO.,LTD. | ERJ2GEJ472X |  |  | PWA BOM |
|  | 610107B00-029-G |  |  | RES,4.7KOhm,+/-5%,1/16W,G,SMD0402 | VISHAY ENTER TECHNO LOGY.INC | CRCW04024K70JNED |  |  | PWA BOM |
| 4 | 311004800-031-G | 1 | 2 | IC,Translator,PCA9617ADPJ,0.8~5.5V,2.2~5.5V,G,TSSOP-8,SMD | NXP SEMICONDUCTORS | PCA9617ADPJ |  | (+)U_I2C_RE2 | PWA BOM |
|  | 311004V00-223-G |  |  | Logic IC,Translator,PCA9617ADMR2G,Vcca=0.8V~5.5V,Vccb=2.2V~5.5V,102ns,Micro8,8P,G | ON SEMICONDUCTOR CORP | PCA9617ADMR2G |  |  | PWA BOM |
| 5 | 3406B6F00-317-G | 0 | 1 | CONN,Header,WTB,2X3,R/A,Bla,2.5mm,15u,G,SMD-6 | MOLEX INCORPORATED | 15-91-2065 |  | (+)J_CPLD_JTAG | PWA BOM |
| 6 | 15-91-2065 | 1 | 0 | CONN,Header,Pin Header,1X6,Bla,2.54mm,10u,G,SMD-6 | MOLEX INCORPORATED | 15-91-2065 |  | (-)J_CPLD_JTAG | PWA BOM |
| OOOOOOOOOOOOOOOOOOOOOOOOOOOOOOOOOOOOOOOOOOOOOOOOOOOOOOOOOOOOOOOOOOOOOOOOOOOOOOOOOOOOOOOOOO | OOOOOOOOOOOOOOOOOOOOOOOOOOOOOOOOOOOOOOOOOOOOOOOOOOOOOOOOOOOOOOOOOOOOOOOOOOOOOOOOOOOOOOOOOO | OOOOOOOOOOOOOOOOOOOOOOOOOOOOOOOOOOOOOOOOOOOOOOOOOOOOOOOOOOOOOOOOOOOOOOOOOOOOOOOOOOOOOOOOOO | OOOOOOOOOOOOOOOOOOOOOOOOOOOOOOOOOOOOOOOOOOOOOOOOOOOOOOOOOOOOOOOOOOOOOOOOOOOOOOOOOOOOOOOOOO | OOOOOOOOOOOOOOOOOOOOOOOOOOOOOOOOOOOOOOOOOOOOOOOOOOOOOOOOOOOOOOOOOOOOOOOOOOOOOOOOOOOOOOOOOO | OOOOOOOOOOOOOOOOOOOOOOOOOOOOOOOOOOOOOOOOOOOOOOOOOOOOOOOOOOOOOOOOOOOOOOOOOOOOOOOOOOOOOOOOOO | OOOOOOOOOOOOOOOOOOOOOOOOOOOOOOOOOOOOOOOOOOOOOOOOOOOOOOOOOOOOOOOOOOOOOOOOOOOOOOOOOOOOOOOOOO | OOOOOOOOOOOOOOOOOOOOOOOOOOOOOOOOOOOOOOOOOOOOOOOOOOOOOOOOOOOOOOOOOOOOOOOOOOOOOOOOOOOOOOOOOO | OOOOOOOOOOOOOOOOOOOOOOOOOOOOOOOOOOOOOOOOOOOOOOOOOOOOOOOOOOOOOOOOOOOOOOOOOOOOOOOOOOOOOOOOOO |  |
| TLA Parts Change |  |  |  |  |  |  |  |  |  |
| Item | Foxconn P/N | Qty | Part Description | Manufacturer Full Name | Manufacturer P/N | RoHS | Location | Remark |  |
| 1 | 7J-004-938 | 1 | L6 LABEL ( 12.7*11.1mm) | FOXCONN / EPD1 | 7J-004-938 | G |  | In Old BOM |  |
| 2 | 1B51GF500-600-G | 1 | 8_MYLAR_HDD_BP_FRONT_POWER9 | 1B51GF500-600-G | 1B51GF500-600-G | G |  | In Old BOM |  |
| BOM Change List Date:Mon Jun 05 11:17:13 GMT+08:00 2017 |  |  |  |  |  |  |  |  |  |
| New BOM file : C:\Barreleye_G2-Tri-mode BPX24-EVT-X00-BOM-X03_20170605_Final.xls |  |  |  |  |  |  |  |  |  |
| Old BOM file : C:\Barreleye_G2-Tri-mode BPX24-EVT-X00-BOM-X03_20170602_Final.xls |  |  |  |  |  |  |  |  |  |
| ##### Add Parts |  |  |  |  |  |  |  |  |  |
| Item | Location | Qty | Foxconn P/N | Part Description | Manufacturer Full Name | Manufacturer P/N | RoHS | Sheet |  |
| ##### Remove Parts |  |  |  |  |  |  |  |  |  |
| Item | Location | Qty | Foxconn P/N | Part Description | Manufacturer Full Name | Manufacturer P/N | RoHS | Sheet |  |
| ##### Change Parts |  |  |  |  |  |  |  |  |  |
| Item | Location | Qty | Foxconn P/N | Part Description | Manufacturer Full Name | Manufacturer P/N | RoHS | Sheet | Remark |
| 1 | C2198,C2208,C2209,C2210,C2211,C2212,C2213,C2214,C2215,C2216,C2217,C2218,C2219,C2220,C2221,C2222,C2223,C2224 | 18 | 62011LU00-015-G | CAP,100nF,+/-10%,X5R,16V,G,SMD0402 | MURATA ELEC. NORTH AMERICA | GRM155R61C104KA88D | G | PWA BOM | In New BOM |
|  |  |  | 620100300-023-G | CAP,100nF,+/-10%,X5R,16V,G,SMD0402 | TAIYO | EMK105BJ104KV-F | G | PWA BOM | In New BOM |
|  |  |  | 620100300-026-G | CAP,100nF,+/-10%,X5R,16V,G,SMD0402 | SAMSUNG SEMICONDUCTOR | CL05A104KO5NNNC | G | PWA BOM | In New BOM |
|  |  |  | 620100300-012-G | CAP,100nF,+/-10%,X5R,16V,G,SMD0402 | WALSIN TECHNOLOGY CORPORATION | 0402X104K160CT | G | PWA BOM | In New BOM |
|  | C2198,C2208,C2209,C2210,C2211,C2212,C2213,C2214,C2215,C2216,C2217,C2218,C2219,C2220,C2221,C2222,C2223,C2224 | 18 | 62011LU00-015-G | CAP,100nF,+/-10%,X5R,16V,G,SMD0402 | MURATA ELEC. NORTH AMERICA | GRM155R61C104KA88D | G | PWA BOM | In Old BOM |
|  |  |  | 620100300-023-G | CAP,100nF,+/-10%,X5R,16V,G,SMD0402 | TAIYO | EMK105BJ104KV-F | G | PWA BOM | In Old BOM |
|  |  |  | 620100300-026-G | CAP,100nF,+/-10%,X5R,16V,G,SMD0402 | SAMSUNG | CL05A104KO5NNNC | G | PWA BOM | In Old BOM |
|  |  |  | 620100300-012-G | CAP,100nF,+/-10%,X5R,16V,G,SMD0402 | WALSIN TECHNOLOGY CORPORATION | 0402X104K160CT | G | PWA BOM | In Old BOM |
| 2 | L1 | 1 | 720101900-015-G | FB,60 Ohm@100MHz,+/-25%,3A,25mOhm,G,SMD0805 | MURATA ELEC. NORTH AMERICA | BLM21PG600SN1D | G | PWA BOM | In New BOM |
|  |  |  | 720101900-026-G | FB,60 Ohm@100MHz,+/-25%,3A,25mOhm,G,SMD0805 | SAMSUNG SEMICONDUCTOR | CIC21P600NE | G | PWA BOM | In New BOM |
|  | L1 | 1 | 720101900-015-G | FB,60 Ohm@100MHz,+/-25%,3A,25mOhm,G,SMD0805 | MURATA ELEC. NORTH AMERICA | BLM21PG600SN1D | G | PWA BOM | In Old BOM |
|  |  |  | 720101900-026-G | FB,60 Ohm@100MHz,+/-25%,3A,25mOhm,G,SMD0805 | SAMSUNG | CIC21P600NE | G | PWA BOM | In Old BOM |
| 3 | PCB | 1 | 0101F2800-000-G | PCB,Zaius-Tri-mode BPX24 EVT-X00,OSP,Red,22L,21.122*3.470,G | GOLD CIRCUIT ELECTRONICS LTD. | 0101F2800-000-G | G | PWA BOM | In New BOM |
|  |  |  | 0101F2800-000-G | PCB,Zaius-Tri-mode BPX24 EVT-X00,OSP,Red,22L,21.122*3.470,G | ZHUHAI FOUNDER PRINTED CIRCUIT BOARD（HK） DEVELOPMENT LIMITED | 0101F2800-000-G | G | PWA BOM | In New BOM |
|  | PCB | 1 | PCB | PCB | PCB | PCB | G | PWA BOM | In Old BOM |
| ##### Change Revision |  |  |  |  |  |  |  |  |  |
| Sheet | REV OF BOM | CUSTOMER | CUSTOMER P/N | PWA PN | PWA DESCRIPTION | PWA REV | DATE | Remark |  |
| OOOOOOOOOOOOOOOOOOOOOOOOOOOOOOOOOOOOOOOOOOOOOOOOOOOOOOOOOOOOOOOOOOOOOOOOOOOOOOOOOOOOOOOOOO | OOOOOOOOOOOOOOOOOOOOOOOOOOOOOOOOOOOOOOOOOOOOOOOOOOOOOOOOOOOOOOOOOOOOOOOOOOOOOOOOOOOOOOOOOO | OOOOOOOOOOOOOOOOOOOOOOOOOOOOOOOOOOOOOOOOOOOOOOOOOOOOOOOOOOOOOOOOOOOOOOOOOOOOOOOOOOOOOOOOOO | OOOOOOOOOOOOOOOOOOOOOOOOOOOOOOOOOOOOOOOOOOOOOOOOOOOOOOOOOOOOOOOOOOOOOOOOOOOOOOOOOOOOOOOOOO | OOOOOOOOOOOOOOOOOOOOOOOOOOOOOOOOOOOOOOOOOOOOOOOOOOOOOOOOOOOOOOOOOOOOOOOOOOOOOOOOOOOOOOOOOO | OOOOOOOOOOOOOOOOOOOOOOOOOOOOOOOOOOOOOOOOOOOOOOOOOOOOOOOOOOOOOOOOOOOOOOOOOOOOOOOOOOOOOOOOOO | OOOOOOOOOOOOOOOOOOOOOOOOOOOOOOOOOOOOOOOOOOOOOOOOOOOOOOOOOOOOOOOOOOOOOOOOOOOOOOOOOOOOOOOOOO | OOOOOOOOOOOOOOOOOOOOOOOOOOOOOOOOOOOOOOOOOOOOOOOOOOOOOOOOOOOOOOOOOOOOOOOOOOOOOOOOOOOOOOOOOO | OOOOOOOOOOOOOOOOOOOOOOOOOOOOOOOOOOOOOOOOOOOOOOOOOOOOOOOOOOOOOOOOOOOOOOOOOOOOOOOOOOOOOOOOOO | OOOOOOOOOOOOOOOOOOOOOOOOOOOOOOOOOOOOOOOOOOOOOOOOOOOOOOOOOOOOOOOOOOOOOOOOOOOOOOOOOOOOOOOOOO |
| Second Source Change |  |  |  |  |  |  |  |  |  |
| Item | Location | Change Type | Foxconn P/N | Part Description | Manufacturer Full Name | Manufacturer P/N | RoHS | Sheet |  |
| OOOOOOOOOOOOOOOOOOOOOOOOOOOOOOOOOOOOOOOOOOOOOOOOOOOOOOOOOOOOOOOOOOOOOOOOOOOOOOOOOOOOOOOOOO | OOOOOOOOOOOOOOOOOOOOOOOOOOOOOOOOOOOOOOOOOOOOOOOOOOOOOOOOOOOOOOOOOOOOOOOOOOOOOOOOOOOOOOOOOO | OOOOOOOOOOOOOOOOOOOOOOOOOOOOOOOOOOOOOOOOOOOOOOOOOOOOOOOOOOOOOOOOOOOOOOOOOOOOOOOOOOOOOOOOOO | OOOOOOOOOOOOOOOOOOOOOOOOOOOOOOOOOOOOOOOOOOOOOOOOOOOOOOOOOOOOOOOOOOOOOOOOOOOOOOOOOOOOOOOOOO | OOOOOOOOOOOOOOOOOOOOOOOOOOOOOOOOOOOOOOOOOOOOOOOOOOOOOOOOOOOOOOOOOOOOOOOOOOOOOOOOOOOOOOOOOO | OOOOOOOOOOOOOOOOOOOOOOOOOOOOOOOOOOOOOOOOOOOOOOOOOOOOOOOOOOOOOOOOOOOOOOOOOOOOOOOOOOOOOOOOOO | OOOOOOOOOOOOOOOOOOOOOOOOOOOOOOOOOOOOOOOOOOOOOOOOOOOOOOOOOOOOOOOOOOOOOOOOOOOOOOOOOOOOOOOOOO | OOOOOOOOOOOOOOOOOOOOOOOOOOOOOOOOOOOOOOOOOOOOOOOOOOOOOOOOOOOOOOOOOOOOOOOOOOOOOOOOOOOOOOOOOO | OOOOOOOOOOOOOOOOOOOOOOOOOOOOOOOOOOOOOOOOOOOOOOOOOOOOOOOOOOOOOOOOOOOOOOOOOOOOOOOOOOOOOOOOOO | OOOOOOOOOOOOOOOOOOOOOOOOOOOOOOOOOOOOOOOOOOOOOOOOOOOOOOOOOOOOOOOOOOOOOOOOOOOOOOOOOOOOOOOOOO |
| Master Materials Change |  |  |  |  |  |  |  |  |  |
| Item | Foxconn P/N | Orig._Usage | New_Usage | Part Description | Manufacturer Full Name | Manufacturer P/N | RoHS | Location | Sheet |
| 1 | 0101F2800-000-G | 0 | 1 | PCB,Zaius-Tri-mode BPX24 EVT-X00,OSP,Red,22L,21.122*3.470,G | GOLD CIRCUIT ELECTRONICS LTD. | 0101F2800-000-G | G | (+)PCB | PWA BOM |
|  | 0101F2800-000-G |  |  | PCB,Zaius-Tri-mode BPX24 EVT-X00,OSP,Red,22L,21.122*3.470,G | ZHUHAI FOUNDER PRINTED CIRCUIT BOARD（HK） DEVELOPMENT LIMITED | 0101F2800-000-G |  |  | PWA BOM |
| 2 | PCB | 1 | 0 | PCB | PCB | PCB | G | (-)PCB | PWA BOM |
| OOOOOOOOOOOOOOOOOOOOOOOOOOOOOOOOOOOOOOOOOOOOOOOOOOOOOOOOOOOOOOOOOOOOOOOOOOOOOOOOOOOOOOOOOO | OOOOOOOOOOOOOOOOOOOOOOOOOOOOOOOOOOOOOOOOOOOOOOOOOOOOOOOOOOOOOOOOOOOOOOOOOOOOOOOOOOOOOOOOOO | OOOOOOOOOOOOOOOOOOOOOOOOOOOOOOOOOOOOOOOOOOOOOOOOOOOOOOOOOOOOOOOOOOOOOOOOOOOOOOOOOOOOOOOOOO | OOOOOOOOOOOOOOOOOOOOOOOOOOOOOOOOOOOOOOOOOOOOOOOOOOOOOOOOOOOOOOOOOOOOOOOOOOOOOOOOOOOOOOOOOO | OOOOOOOOOOOOOOOOOOOOOOOOOOOOOOOOOOOOOOOOOOOOOOOOOOOOOOOOOOOOOOOOOOOOOOOOOOOOOOOOOOOOOOOOOO | OOOOOOOOOOOOOOOOOOOOOOOOOOOOOOOOOOOOOOOOOOOOOOOOOOOOOOOOOOOOOOOOOOOOOOOOOOOOOOOOOOOOOOOOOO | OOOOOOOOOOOOOOOOOOOOOOOOOOOOOOOOOOOOOOOOOOOOOOOOOOOOOOOOOOOOOOOOOOOOOOOOOOOOOOOOOOOOOOOOOO | OOOOOOOOOOOOOOOOOOOOOOOOOOOOOOOOOOOOOOOOOOOOOOOOOOOOOOOOOOOOOOOOOOOOOOOOOOOOOOOOOOOOOOOOOO | OOOOOOOOOOOOOOOOOOOOOOOOOOOOOOOOOOOOOOOOOOOOOOOOOOOOOOOOOOOOOOOOOOOOOOOOOOOOOOOOOOOOOOOOOO | OOOOOOOOOOOOOOOOOOOOOOOOOOOOOOOOOOOOOOOOOOOOOOOOOOOOOOOOOOOOOOOOOOOOOOOOOOOOOOOOOOOOOOOOOO |
| TLA Parts Change |  |  |  |  |  |  |  |  |  |
| Item | Foxconn P/N | Qty | Part Description | Manufacturer Full Name | Manufacturer P/N | RoHS | Location | Remark | BOM |
| 1 | 1B51GF500-600-G 1B51KUN00-600-G | 1 | 8_MYLAR_HDD_BP_FRONT_POWER9 8_MYLAR-HDD-BP-FRONT_BG2 | FOXCONN / EPD5 | 1B51GF500-600-G  1B51KUN00-600-G | G |  | Rev.X02 Rev.X01 | In New BOM |
|  | 1B51GF500-600-G 1B51KUN00-600-G | 1 | 8_MYLAR_HDD_BP_FRONT_POWER9 | FOXCONN / EPD5 | 1B51GF500-600-G | G |  | Rev.X02 | In Old BOM |
| BOM Change List Date:Fri Aug 25 09:36:54 CST 2017 |  |  |  |  |  |  |  |  |  |
| New BOM file : E:\barreleye g2\0824\foxbis\new BOM\BPX24 25.xls |  |  |  |  |  |  |  |  |  |
| Old BOM file : E:\barreleye g2\0824\foxbis\old bom\Barreleye_G2-Tri-mode BPX24-EVT-X00-BOM-X03_20170605_Final.xls |  |  |  |  |  |  |  |  |  |
| ##### Add Parts |  |  |  |  |  |  |  |  |  |
| Item | Location | Qty | Foxconn P/N | Part Description | Manufacturer Full Name | Manufacturer P/N | RoHS | Sheet |  |
| ##### Remove Parts |  |  |  |  |  |  |  |  |  |
| Item | Location | Qty | Foxconn P/N | Part Description | Manufacturer Full Name | Manufacturer P/N | RoHS | Sheet |  |
| ##### Change Parts |  |  |  |  |  |  |  |  |  |
| Item | Location | Qty | Foxconn P/N | Part Description | Manufacturer Full Name | Manufacturer P/N | RoHS | Sheet | Remark |
| 1 | PSTL2,PFTL2,PETL2 | 3 | 630341400-088-G | IND,22nH@1MHz,+/-20%,19A,368uOhm,SHLD,G,SMD | COOPER BUSSMANN, INC. | FP0404R1-R022-R | G | PWA BOM | In New BOM |
|  |  |  | 630362G00-065-G | 22nH@100KHz,+/-20%,19A,0.32mOhm,SHLD,G,SMD | Delta | HCB0430-220 | G | PWA BOM | In New BOM |
|  | PSTL2,PFTL2,PETL2 | 3 | 630341400-088-G | IND,22nH@1MHz,+/-20%,19A,368uOhm,SHLD,G,SMD | COOPER BUSSMANN, INC. | FP0404R1-R022-R | G | PWA BOM | In Old BOM |
|  |  |  | HCB0430-220 | IND,HCB0430-220 | Delta | HCB0430-220 | G | PWA BOM | In Old BOM |
| 2 | PSRL2 | 1 | 63032PP00-088-G | IND,4.7uH@100KHz,+/-20%,5.5A,40mOhm,SHLD,G,SMD | COOPER BUSSMANN, INC. | HCM0703-4R7-R | G | PWA BOM | In New BOM |
|  |  |  | 63030PW00-034-G | Coil Ind,Shielded(SHLD),4.7uH@100KHz,+/-20%,5.5A,40mOhm,SMD,7.3*6.6*3.0,G | CYNTEC CO. LTD | PCMC063T-4R7MN | G | PWA BOM | In New BOM |
|  |  |  | 63031AD04-129-G | IND,4.7uH@100KHz,+/-20%,5.5A,40mOhm,SHLD,G,SMD | MAG.LAYERS, SCIENTIFIC-TECHNICS (KUNSHAN) CO., LTD. | SPS-06CZ-4R7M-V1 | G | PWA BOM | In New BOM |
|  | PSRL2 | 1 | 63032PP00-088-G | IND,4.7uH@100KHz,+/-20%,5.5A,40mOhm,SHLD,G,SMD | COOPER BUSSMANN, INC. | HCM0703-4R7-R | G | PWA BOM | In Old BOM |
|  |  |  | 63030PW00-034-G | Coil Ind,Shielded(SHLD),4.7uH@100KHz,+/-20%,5.5A,40mOhm,SMD,7.3*6.6*3.0,G | CYNTEC CO. LTD | PCMC063T-4R7MN | G | PWA BOM | In Old BOM |
|  |  |  | SPS-06CZ-4R7M-V1 | IND,SPS-06CZ-4R7M-V1 | MAG.LAYERS, SCIENTIFIC-TECHNICS (KUNSHAN) CO., LTD. | SPS-06CZ-4R7M-V1 | G | PWA BOM | In Old BOM |
| 3 | R1408,R1449 | 2 | 610107L00-017-G | RES,1 Ohm,+/-5%,1/10W,G,SMD0603 | KOA SPEER ELECTRONICS, INC. | RK73B1JTTD1R0J | G | PWA BOM | In New BOM |
|  |  |  | 610107L00-011-G | RES,1 Ohm,+/-5%,1/10W,G,SMD0603 | YAGEO CORPORATION COMPONENT | RC0603JR-071RL | G | PWA BOM | In New BOM |
|  |  |  | 610107L00-012-G | RES,1 Ohm,+/-5%,1/10W,G,SMD0603 | WALSIN TECHNOLOGY CORPORATION | WR06X1R0JTL | G | PWA BOM | In New BOM |
|  |  |  | 610107L00-044-G | RES,1 Ohm,+/-5%,1/10W,G,SMD0603 | TA-I TECHNOLOGY CO., LTD | RM06JTN1R0 | G | PWA BOM | In New BOM |
|  | R1408,R1449 | 2 | 610107L00-017-G | RES,1 Ohm,+/-5%,1/10W,G,SMD0603 | KOA SPEER ELECTRONICS, INC. | RK73B1JTTD1R0J | G | PWA BOM | In Old BOM |
|  |  |  | 610107L00-011-G | RES,1 Ohm,+/-5%,1/10W,G,SMD0603 | YAGEO CORPORATION COMPONENT | RC0603JR-071RL |  | PWA BOM | In Old BOM |
|  |  |  | 610107L00-012-G | RES,1 Ohm,+/-5%,1/10W,G,SMD0603 | WALSIN TECHNOLOGY CORPORATION | WR06X1R0JTL |  | PWA BOM | In Old BOM |
|  |  |  | 610107L00-044-G | RES,1 Ohm,+/-5%,1/10W,G,SMD0603 | TA-I TECHNOLOGY CO., LTD | RM06JTN1R0 |  | PWA BOM | In Old BOM |
| 4 | PCB | 1 | PCB | PCB | PCB | PCB | G | PWA BOM | In New BOM |
|  | PCB | 1 | 0101F2800-000-G | PCB,Zaius-Tri-mode BPX24 EVT-X00,OSP,Red,22L,21.122*3.470,G | GOLD CIRCUIT ELECTRONICS LTD. | 0101F2800-000-G | G | PWA BOM | In Old BOM |
| 5 | U248 | 1 | 220106A00-413-G | IC,PLD,10M08SCU169C8G,3.3V,116MHz,G,BGA-169,SMD | ALTERA CORPORATION | 10M08SCU169C8G | G | PWA BOM | In New BOM |
|  | U248 | 1 | 220107K00-413-G | IC,PLD,10M02SCU169C8G,116MHz,3.3V,G,UBGA-169,SMD | ALTERA CORPORATION | 10M02SCU169C8G | G | PWA BOM | In Old BOM |
| 6 | J_CPLD_JTAG | 1 | ZP91-0155C-1221 | CONN,Header,WTB,2X3,R/A,Bla,2.5mm,15u,G,SMD-6 | CENLINK | ZP91-0155C-1221 | G | PWA BOM | In New BOM |
|  | J_CPLD_JTAG | 1 | 3406B6F00-317-G | CONN,Header,WTB,2X3,R/A,Bla,2.5mm,15u,G,SMD-6 | MOLEX INCORPORATED | 15-91-2065 | G | PWA BOM | In Old BOM |
| ##### Change Revision |  |  |  |  |  |  |  |  |  |
| Sheet | REV OF BOM | CUSTOMER | CUSTOMER P/N | PWA PN | PWA DESCRIPTION | PWA REV | DATE | Remark |  |
| PWA BOM |  | Customer |  |  |  |  |  | In New BOM |  |
| PWA BOM | X03 | Customer |  |  |  |  | 6/5/17 | In Old BOM |  |
| OOOOOOOOOOOOOOOOOOOOOOOOOOOOOOOOOOOOOOOOOOOOOOOOOOOOOOOOOOOOOOOOOOOOOOOOOOOOOOOOOOOOOOOOOO | OOOOOOOOOOOOOOOOOOOOOOOOOOOOOOOOOOOOOOOOOOOOOOOOOOOOOOOOOOOOOOOOOOOOOOOOOOOOOOOOOOOOOOOOOO | OOOOOOOOOOOOOOOOOOOOOOOOOOOOOOOOOOOOOOOOOOOOOOOOOOOOOOOOOOOOOOOOOOOOOOOOOOOOOOOOOOOOOOOOOO | OOOOOOOOOOOOOOOOOOOOOOOOOOOOOOOOOOOOOOOOOOOOOOOOOOOOOOOOOOOOOOOOOOOOOOOOOOOOOOOOOOOOOOOOOO | OOOOOOOOOOOOOOOOOOOOOOOOOOOOOOOOOOOOOOOOOOOOOOOOOOOOOOOOOOOOOOOOOOOOOOOOOOOOOOOOOOOOOOOOOO | OOOOOOOOOOOOOOOOOOOOOOOOOOOOOOOOOOOOOOOOOOOOOOOOOOOOOOOOOOOOOOOOOOOOOOOOOOOOOOOOOOOOOOOOOO | OOOOOOOOOOOOOOOOOOOOOOOOOOOOOOOOOOOOOOOOOOOOOOOOOOOOOOOOOOOOOOOOOOOOOOOOOOOOOOOOOOOOOOOOOO | OOOOOOOOOOOOOOOOOOOOOOOOOOOOOOOOOOOOOOOOOOOOOOOOOOOOOOOOOOOOOOOOOOOOOOOOOOOOOOOOOOOOOOOOOO | OOOOOOOOOOOOOOOOOOOOOOOOOOOOOOOOOOOOOOOOOOOOOOOOOOOOOOOOOOOOOOOOOOOOOOOOOOOOOOOOOOOOOOOOOO | OOOOOOOOOOOOOOOOOOOOOOOOOOOOOOOOOOOOOOOOOOOOOOOOOOOOOOOOOOOOOOOOOOOOOOOOOOOOOOOOOOOOOOOOOO |
| Second Source Change |  |  |  |  |  |  |  |  |  |
| Item | Location | Change Type | Foxconn P/N | Part Description | Manufacturer Full Name | Manufacturer P/N | RoHS | Sheet |  |
| 1 | PSTL2,PFTL2,PETL2 |  | 630341400-088-G | IND,22nH@1MHz,+/-20%,19A,368uOhm,SHLD,G,SMD | COOPER BUSSMANN, INC. | FP0404R1-R022-R | G | PWA BOM |  |
|  |  | ADD | 630362G00-065-G | 22nH@100KHz,+/-20%,19A,0.32mOhm,SHLD,G,SMD | Delta | HCB0430-220 | G | PWA BOM |  |
|  |  | Delete | HCB0430-220 | IND,HCB0430-220 | Delta | HCB0430-220 | G | PWA BOM |  |
| 2 | PSRL2 |  | 63032PP00-088-G | IND,4.7uH@100KHz,+/-20%,5.5A,40mOhm,SHLD,G,SMD | COOPER BUSSMANN, INC. | HCM0703-4R7-R | G | PWA BOM |  |
|  |  | NO | 63030PW00-034-G | Coil Ind,Shielded(SHLD),4.7uH@100KHz,+/-20%,5.5A,40mOhm,SMD,7.3*6.6*3.0,G | CYNTEC CO. LTD | PCMC063T-4R7MN | G | PWA BOM |  |
|  |  | ADD | 63031AD04-129-G | IND,4.7uH@100KHz,+/-20%,5.5A,40mOhm,SHLD,G,SMD | MAG.LAYERS, SCIENTIFIC-TECHNICS (KUNSHAN) CO., LTD. | SPS-06CZ-4R7M-V1 | G | PWA BOM |  |
|  |  | Delete | SPS-06CZ-4R7M-V1 | IND,SPS-06CZ-4R7M-V1 | MAG.LAYERS, SCIENTIFIC-TECHNICS (KUNSHAN) CO., LTD. | SPS-06CZ-4R7M-V1 | G | PWA BOM |  |
| OOOOOOOOOOOOOOOOOOOOOOOOOOOOOOOOOOOOOOOOOOOOOOOOOOOOOOOOOOOOOOOOOOOOOOOOOOOOOOOOOOOOOOOOOO | OOOOOOOOOOOOOOOOOOOOOOOOOOOOOOOOOOOOOOOOOOOOOOOOOOOOOOOOOOOOOOOOOOOOOOOOOOOOOOOOOOOOOOOOOO | OOOOOOOOOOOOOOOOOOOOOOOOOOOOOOOOOOOOOOOOOOOOOOOOOOOOOOOOOOOOOOOOOOOOOOOOOOOOOOOOOOOOOOOOOO | OOOOOOOOOOOOOOOOOOOOOOOOOOOOOOOOOOOOOOOOOOOOOOOOOOOOOOOOOOOOOOOOOOOOOOOOOOOOOOOOOOOOOOOOOO | OOOOOOOOOOOOOOOOOOOOOOOOOOOOOOOOOOOOOOOOOOOOOOOOOOOOOOOOOOOOOOOOOOOOOOOOOOOOOOOOOOOOOOOOOO | OOOOOOOOOOOOOOOOOOOOOOOOOOOOOOOOOOOOOOOOOOOOOOOOOOOOOOOOOOOOOOOOOOOOOOOOOOOOOOOOOOOOOOOOOO | OOOOOOOOOOOOOOOOOOOOOOOOOOOOOOOOOOOOOOOOOOOOOOOOOOOOOOOOOOOOOOOOOOOOOOOOOOOOOOOOOOOOOOOOOO | OOOOOOOOOOOOOOOOOOOOOOOOOOOOOOOOOOOOOOOOOOOOOOOOOOOOOOOOOOOOOOOOOOOOOOOOOOOOOOOOOOOOOOOOOO | OOOOOOOOOOOOOOOOOOOOOOOOOOOOOOOOOOOOOOOOOOOOOOOOOOOOOOOOOOOOOOOOOOOOOOOOOOOOOOOOOOOOOOOOOO | OOOOOOOOOOOOOOOOOOOOOOOOOOOOOOOOOOOOOOOOOOOOOOOOOOOOOOOOOOOOOOOOOOOOOOOOOOOOOOOOOOOOOOOOOO |
| Master Materials Change |  |  |  |  |  |  |  |  |  |
| Item | Foxconn P/N | Orig._Usage | New_Usage | Part Description | Manufacturer Full Name | Manufacturer P/N | RoHS | Location | Sheet |
| 1 | PCB | 0 | 1 | PCB | PCB | PCB | G | (+)PCB | PWA BOM |
| 2 | 220106A00-413-G | 0 | 1 | IC,PLD,10M08SCU169C8G,3.3V,116MHz,G,BGA-169,SMD | ALTERA CORPORATION | 10M08SCU169C8G | G | (+)U248 | PWA BOM |
| 3 | ZP91-0155C-1221 | 0 | 1 | CONN,Header,WTB,2X3,R/A,Bla,2.5mm,15u,G,SMD-6 | CENLINK | ZP91-0155C-1221 | G | (+)J_CPLD_JTAG | PWA BOM |
| 4 | 0101F2800-000-G | 1 | 0 | PCB,Zaius-Tri-mode BPX24 EVT-X00,OSP,Red,22L,21.122*3.470,G | GOLD CIRCUIT ELECTRONICS LTD. | 0101F2800-000-G | G | (-)PCB | PWA BOM |
| 5 | 220107K00-413-G | 1 | 0 | IC,PLD,10M02SCU169C8G,116MHz,3.3V,G,UBGA-169,SMD | ALTERA CORPORATION | 10M02SCU169C8G | G | (-)U248 | PWA BOM |
| 6 | 3406B6F00-317-G | 1 | 0 | CONN,Header,WTB,2X3,R/A,Bla,2.5mm,15u,G,SMD-6 | MOLEX INCORPORATED | 15-91-2065 | G | (-)J_CPLD_JTAG | PWA BOM |
| OOOOOOOOOOOOOOOOOOOOOOOOOOOOOOOOOOOOOOOOOOOOOOOOOOOOOOOOOOOOOOOOOOOOOOOOOOOOOOOOOOOOOOOOOO | OOOOOOOOOOOOOOOOOOOOOOOOOOOOOOOOOOOOOOOOOOOOOOOOOOOOOOOOOOOOOOOOOOOOOOOOOOOOOOOOOOOOOOOOOO | OOOOOOOOOOOOOOOOOOOOOOOOOOOOOOOOOOOOOOOOOOOOOOOOOOOOOOOOOOOOOOOOOOOOOOOOOOOOOOOOOOOOOOOOOO | OOOOOOOOOOOOOOOOOOOOOOOOOOOOOOOOOOOOOOOOOOOOOOOOOOOOOOOOOOOOOOOOOOOOOOOOOOOOOOOOOOOOOOOOOO | OOOOOOOOOOOOOOOOOOOOOOOOOOOOOOOOOOOOOOOOOOOOOOOOOOOOOOOOOOOOOOOOOOOOOOOOOOOOOOOOOOOOOOOOOO | OOOOOOOOOOOOOOOOOOOOOOOOOOOOOOOOOOOOOOOOOOOOOOOOOOOOOOOOOOOOOOOOOOOOOOOOOOOOOOOOOOOOOOOOOO | OOOOOOOOOOOOOOOOOOOOOOOOOOOOOOOOOOOOOOOOOOOOOOOOOOOOOOOOOOOOOOOOOOOOOOOOOOOOOOOOOOOOOOOOOO | OOOOOOOOOOOOOOOOOOOOOOOOOOOOOOOOOOOOOOOOOOOOOOOOOOOOOOOOOOOOOOOOOOOOOOOOOOOOOOOOOOOOOOOOOO | OOOOOOOOOOOOOOOOOOOOOOOOOOOOOOOOOOOOOOOOOOOOOOOOOOOOOOOOOOOOOOOOOOOOOOOOOOOOOOOOOOOOOOOOOO | OOOOOOOOOOOOOOOOOOOOOOOOOOOOOOOOOOOOOOOOOOOOOOOOOOOOOOOOOOOOOOOOOOOOOOOOOOOOOOOOOOOOOOOOOO |
| TLA Parts Change |  |  |  |  |  |  |  |  |  |
| Item | Foxconn P/N | Qty | Part Description | Manufacturer Full Name | Manufacturer P/N | RoHS | Location | Remark | BOM |
| BOM Change List Date:Thu Aug 31 16:50:13 GMT+08:00 2017 |  |  |  |  |  |  |  |  |  |
| New BOM file : E:\barreleye g2\0830\EXPANDER BPX24\Barreleye-G2_Tri-mode BPX24-DVT-X01-BOM-X04-20170831.xls |  |  |  |  |  |  |  |  |  |
| Old BOM file : E:\barreleye g2\0830\EXPANDER BPX24\BPX24 0825.xls |  |  |  |  |  |  |  |  |  |
| ##### Add Parts |  |  |  |  |  |  |  |  |  |
| Item | Location | Qty | Foxconn P/N | Part Description | Manufacturer Full Name | Manufacturer P/N | RoHS | Sheet |  |
| 1 | C2271 | 1 | 620101T02-015-G | CAP,100nF,+/-10%,X7R,16V,G,SMD0402 | MURATA ELEC. NORTH AMERICA | GRM155R71C104K | G | PWA BOM |  |
|  |  |  | 620101T00-012-G | CAP,100nF,+/-10%,X7R,16V,G,SMD0402 | WALSIN TECHNOLOGY CORPORATION | 0402B104K160CT | G | PWA BOM |  |
|  |  |  | 620101T00-026-G | CAP,100nF,+/-10%,X7R,16V,G,SMD0402 | SAMSUNG SEMICONDUCTOR | CL05B104KO5NNNC | G | PWA BOM |  |
|  |  |  | 620101T00-015-G | CAP,100nF,+/-10%,X7R,16V,G,SMD0402 | MURATA ELEC. NORTH AMERICA | GRM155R71C104KA88D | G | PWA BOM |  |
| 2 | R2152,R2153,R2154,R2155 | 4 | 610107A00-017-G | RES,0 Ohm,+/-5%,1/16W,G,SMD0402 | KOA SPEER ELECTRONICS, INC. | RK73Z1ETTP | G | PWA BOM |  |
|  |  |  | 610107A00-012-G | RES,0 Ohm,+/-5%,1/16W,G,SMD0402 | WALSIN TECHNOLOGY CORPORATION | WR04X000PTL | G | PWA BOM |  |
|  |  |  | 610107A00-011-G | RES,0 Ohm,+/-5%,1/16W,G,SMD0402 | YAGEO CORPORATION COMPONENT | RC0402JR-070RL | G | PWA BOM |  |
|  |  |  | 610107A00-044-G | RES,0 Ohm,+/-5%,1/16W,G,SMD0402 | TA-I TECHNOLOGY CO., LTD | RM04JTN0 | G | PWA BOM |  |
|  |  |  | 610107A00-024-G | RES,0 Ohm,+/-5%,1/16W,G,SMD0402 | PANASONIC INDUSTRIAL CO.,LTD. | ERJ2GE0R00X | G | PWA BOM |  |
|  |  |  | 610107A00-029-G | RES,0 Ohm,+/-5%,1/16W,G,SMD0402 | VISHAY ENTER TECHNO LOGY.INC | CRCW04020000Z0ED | G | PWA BOM |  |
| ##### Remove Parts |  |  |  |  |  |  |  |  |  |
| Item | Location | Qty | Foxconn P/N | Part Description | Manufacturer Full Name | Manufacturer P/N | RoHS | Sheet |  |
| 1 | R229,R230 | 2 | 61010LA00-017-G | RES,4.7KOhm,+/-1%,1/16W,G,SMD0402 | KOA SPEER ELECTRONICS, INC. | RK73H1ETTP4701F | G | PWA BOM |  |
|  |  |  | 61010LA00-012-G | RES,4.7KOhm,+/-1%,1/16W,G,SMD0402 | WALSIN TECHNOLOGY CORPORATION | WR04X4701FTL | G | PWA BOM |  |
|  |  |  | 61010LA00-011-G | RES,4.7KOhm,+/-1%,1/16W,G,SMD0402 | YAGEO CORPORATION COMPONENT | RC0402FR-074K7L | G | PWA BOM |  |
|  |  |  | 61010LA00-044-G | RES,4.7KOhm,+/-1%,1/16W,G,SMD0402 | TA-I TECHNOLOGY CO., LTD | RM04FTN4701 | G | PWA BOM |  |
| ##### Change Parts |  |  |  |  |  |  |  |  |  |
| Item | Location | Qty | Foxconn P/N | Part Description | Manufacturer Full Name | Manufacturer P/N | RoHS | Sheet | Remark |
| 1 | R251,R252 | 2 | 610118100-017-G | RES,1.4KOhm,+/-1%,1/16W,G,SMD0402 | KOA SPEER ELECTRONICS, INC. | RK73H1ETTP1401F | G | PWA BOM | In New BOM |
|  | R251,R252 | 2 | 61010LA00-017-G | RES,4.7KOhm,+/-1%,1/16W,G,SMD0402 | KOA SPEER ELECTRONICS, INC. | RK73H1ETTP4701F | G | PWA BOM | In Old BOM |
|  |  |  | 61010LA00-012-G | RES,4.7KOhm,+/-1%,1/16W,G,SMD0402 | WALSIN TECHNOLOGY CORPORATION | WR04X4701FTL | G | PWA BOM | In Old BOM |
|  |  |  | 61010LA00-011-G | RES,4.7KOhm,+/-1%,1/16W,G,SMD0402 | YAGEO CORPORATION COMPONENT | RC0402FR-074K7L | G | PWA BOM | In Old BOM |
|  |  |  | 61010LA00-044-G | RES,4.7KOhm,+/-1%,1/16W,G,SMD0402 | TA-I TECHNOLOGY CO., LTD | RM04FTN4701 | G | PWA BOM | In Old BOM |
| 2 | R1313,R1785,R1787,R1788,R1791,R1793,R1795,R1796,R1799,R1800,R1803,R1804,R1807,R1808,R1811,R1812,R1815,R1816,R1819,R1820,R1823,R1824,R1827,R1828 | 24 | 61011MV00-017-G | RES,510 Ohm,+/-1%,1/16W,G,SMD0402 | KOA SPEER ELECTRONICS, INC. | RK73H1ETTP5100F | G | PWA BOM | In New BOM |
|  | R1313,R1785,R1787,R1788,R1791,R1793,R1795,R1796,R1799,R1800,R1803,R1804,R1807,R1808,R1811,R1812,R1815,R1816,R1819,R1820,R1823,R1824,R1827,R1828 | 24 | 61100AH00-017-G | RES,10KOhm,+/-0.5%,1/16W,G,SMD0402 | KOA SPEER ELECTRONICS, INC. | RN731ETTP1002D25 | G | PWA BOM | In Old BOM |
|  |  |  | 61100AH00-012-G | RES,10KOhm,+/-0.5%,1/16W,G,SMD0402 | WALSIN TECHNOLOGY CORPORATION | WF04U1002DTL | G | PWA BOM | In Old BOM |
|  |  |  | 61100AH00-011-G | RES,10KOhm,+/-0.5%,1/16W,G,SMD0402 | YAGEO CORPORATION COMPONENT | RT0402DRE0710KL | G | PWA BOM | In Old BOM |
|  |  |  | 61100AH00-044-G | RES,10KOhm,+/-0.5%,1/16W,G,SMD0402 | TA-I TECHNOLOGY CO., LTD | RB04DTP1002 | G | PWA BOM | In Old BOM |
| 3 | R1314,R1786,R1789,R1790,R1792,R1794,R1797,R1798,R1801,R1802,R1805,R1806,R1809,R1810,R1813,R1814,R1817,R1818,R1821,R1822,R1825,R1826,R1829,R1830 | 24 | 61011FA00-017-G | RES,1.02KOhm,+/-1%,1/16W,G,SMD0402 | KOA SPEER ELECTRONICS, INC. | RK73H1ETTP1021F | G | PWA BOM | In New BOM |
|  | R1314,R1786,R1789,R1790,R1792,R1794,R1797,R1798,R1801,R1802,R1805,R1806,R1809,R1810,R1813,R1814,R1817,R1818,R1821,R1822,R1825,R1826,R1829,R1830 | 24 | 61010FG00-017-G | RES,20KOhm,+/-5%,1/16W,G,SMD0402 | KOA SPEER ELECTRONICS, INC. | RK73B1ETTP203J | G | PWA BOM | In Old BOM |
|  |  |  | 61010FG00-012-G | RES,20KOhm,+/-5%,1/16W,G,SMD0402 | WALSIN TECHNOLOGY CORPORATION | WR04X203JTL | G | PWA BOM | In Old BOM |
|  |  |  | 61010FG00-011-G | RES,20KOhm,+/-5%,1/16W,G,SMD0402 | YAGEO CORPORATION COMPONENT | RC0402JR-0720KL | G | PWA BOM | In Old BOM |
| 4 | J_CPLD_JTAG | 1 | 3406B6F00-317-G | CONN,Header,WTB,2X3,R/A,Bla,2.5mm,15u,G,SMD-6 | MOLEX INCORPORATED | 15-91-2065 | G | PWA BOM | In New BOM |
|  | J_CPLD_JTAG | 1 | ZP91-0155C-1221 | CONN,Header,WTB,2X3,R/A,Bla,2.5mm,15u,G,SMD-6 | CENLINK | ZP91-0155C-1221 | G | PWA BOM | In Old BOM |
| ##### Change Revision |  |  |  |  |  |  |  |  |  |
| Sheet | REV OF BOM | CUSTOMER | CUSTOMER P/N | PWA PN | PWA DESCRIPTION | PWA REV | DATE | Remark |  |
| OOOOOOOOOOOOOOOOOOOOOOOOOOOOOOOOOOOOOOOOOOOOOOOOOOOOOOOOOOOOOOOOOOOOOOOOOOOOOOOOOOOOOOOOOO | OOOOOOOOOOOOOOOOOOOOOOOOOOOOOOOOOOOOOOOOOOOOOOOOOOOOOOOOOOOOOOOOOOOOOOOOOOOOOOOOOOOOOOOOOO | OOOOOOOOOOOOOOOOOOOOOOOOOOOOOOOOOOOOOOOOOOOOOOOOOOOOOOOOOOOOOOOOOOOOOOOOOOOOOOOOOOOOOOOOOO | OOOOOOOOOOOOOOOOOOOOOOOOOOOOOOOOOOOOOOOOOOOOOOOOOOOOOOOOOOOOOOOOOOOOOOOOOOOOOOOOOOOOOOOOOO | OOOOOOOOOOOOOOOOOOOOOOOOOOOOOOOOOOOOOOOOOOOOOOOOOOOOOOOOOOOOOOOOOOOOOOOOOOOOOOOOOOOOOOOOOO | OOOOOOOOOOOOOOOOOOOOOOOOOOOOOOOOOOOOOOOOOOOOOOOOOOOOOOOOOOOOOOOOOOOOOOOOOOOOOOOOOOOOOOOOOO | OOOOOOOOOOOOOOOOOOOOOOOOOOOOOOOOOOOOOOOOOOOOOOOOOOOOOOOOOOOOOOOOOOOOOOOOOOOOOOOOOOOOOOOOOO | OOOOOOOOOOOOOOOOOOOOOOOOOOOOOOOOOOOOOOOOOOOOOOOOOOOOOOOOOOOOOOOOOOOOOOOOOOOOOOOOOOOOOOOOOO | OOOOOOOOOOOOOOOOOOOOOOOOOOOOOOOOOOOOOOOOOOOOOOOOOOOOOOOOOOOOOOOOOOOOOOOOOOOOOOOOOOOOOOOOOO | OOOOOOOOOOOOOOOOOOOOOOOOOOOOOOOOOOOOOOOOOOOOOOOOOOOOOOOOOOOOOOOOOOOOOOOOOOOOOOOOOOOOOOOOOO |
| Second Source Change |  |  |  |  |  |  |  |  |  |
| Item | Location | Change Type | Foxconn P/N | Part Description | Manufacturer Full Name | Manufacturer P/N | RoHS | Sheet |  |
| OOOOOOOOOOOOOOOOOOOOOOOOOOOOOOOOOOOOOOOOOOOOOOOOOOOOOOOOOOOOOOOOOOOOOOOOOOOOOOOOOOOOOOOOOO | OOOOOOOOOOOOOOOOOOOOOOOOOOOOOOOOOOOOOOOOOOOOOOOOOOOOOOOOOOOOOOOOOOOOOOOOOOOOOOOOOOOOOOOOOO | OOOOOOOOOOOOOOOOOOOOOOOOOOOOOOOOOOOOOOOOOOOOOOOOOOOOOOOOOOOOOOOOOOOOOOOOOOOOOOOOOOOOOOOOOO | OOOOOOOOOOOOOOOOOOOOOOOOOOOOOOOOOOOOOOOOOOOOOOOOOOOOOOOOOOOOOOOOOOOOOOOOOOOOOOOOOOOOOOOOOO | OOOOOOOOOOOOOOOOOOOOOOOOOOOOOOOOOOOOOOOOOOOOOOOOOOOOOOOOOOOOOOOOOOOOOOOOOOOOOOOOOOOOOOOOOO | OOOOOOOOOOOOOOOOOOOOOOOOOOOOOOOOOOOOOOOOOOOOOOOOOOOOOOOOOOOOOOOOOOOOOOOOOOOOOOOOOOOOOOOOOO | OOOOOOOOOOOOOOOOOOOOOOOOOOOOOOOOOOOOOOOOOOOOOOOOOOOOOOOOOOOOOOOOOOOOOOOOOOOOOOOOOOOOOOOOOO | OOOOOOOOOOOOOOOOOOOOOOOOOOOOOOOOOOOOOOOOOOOOOOOOOOOOOOOOOOOOOOOOOOOOOOOOOOOOOOOOOOOOOOOOOO | OOOOOOOOOOOOOOOOOOOOOOOOOOOOOOOOOOOOOOOOOOOOOOOOOOOOOOOOOOOOOOOOOOOOOOOOOOOOOOOOOOOOOOOOOO | OOOOOOOOOOOOOOOOOOOOOOOOOOOOOOOOOOOOOOOOOOOOOOOOOOOOOOOOOOOOOOOOOOOOOOOOOOOOOOOOOOOOOOOOOO |
| Master Materials Change |  |  |  |  |  |  |  |  |  |
| Item | Foxconn P/N | Orig._Usage | New_Usage | Part Description | Manufacturer Full Name | Manufacturer P/N | RoHS | Location | Sheet |
| 1 | 620101T02-015-G | 143 | 144 | CAP,100nF,+/-10%,X7R,16V,G,SMD0402 | MURATA ELEC. NORTH AMERICA | GRM155R71C104K | G | (+)C2271 | PWA BOM |
|  | 620101T00-012-G |  |  | CAP,100nF,+/-10%,X7R,16V,G,SMD0402 | WALSIN TECHNOLOGY CORPORATION | 0402B104K160CT |  |  | PWA BOM |
|  | 620101T00-026-G |  |  | CAP,100nF,+/-10%,X7R,16V,G,SMD0402 | SAMSUNG SEMICONDUCTOR | CL05B104KO5NNNC |  |  | PWA BOM |
|  | 620101T00-015-G |  |  | CAP,100nF,+/-10%,X7R,16V,G,SMD0402 | MURATA ELEC. NORTH AMERICA | GRM155R71C104KA88D |  |  | PWA BOM |
| 2 | 61010LA00-017-G | 49 | 45 | RES,4.7KOhm,+/-1%,1/16W,G,SMD0402 | KOA SPEER ELECTRONICS, INC. | RK73H1ETTP4701F | G | (-)R229,R230,R251,R252 | PWA BOM |
|  | 61010LA00-012-G |  |  | RES,4.7KOhm,+/-1%,1/16W,G,SMD0402 | WALSIN TECHNOLOGY CORPORATION | WR04X4701FTL |  |  | PWA BOM |
|  | 61010LA00-011-G |  |  | RES,4.7KOhm,+/-1%,1/16W,G,SMD0402 | YAGEO CORPORATION COMPONENT | RC0402FR-074K7L |  |  | PWA BOM |
|  | 61010LA00-044-G |  |  | RES,4.7KOhm,+/-1%,1/16W,G,SMD0402 | TA-I TECHNOLOGY CO., LTD | RM04FTN4701 |  |  | PWA BOM |
| 3 | 610107A00-017-G | 121 | 125 | RES,0 Ohm,+/-5%,1/16W,G,SMD0402 | KOA SPEER ELECTRONICS, INC. | RK73Z1ETTP | G | (+)R2152,R2153,R2154,R2155 | PWA BOM |
|  | 610107A00-012-G |  |  | RES,0 Ohm,+/-5%,1/16W,G,SMD0402 | WALSIN TECHNOLOGY CORPORATION | WR04X000PTL |  |  | PWA BOM |
|  | 610107A00-011-G |  |  | RES,0 Ohm,+/-5%,1/16W,G,SMD0402 | YAGEO CORPORATION COMPONENT | RC0402JR-070RL |  |  | PWA BOM |
|  | 610107A00-044-G |  |  | RES,0 Ohm,+/-5%,1/16W,G,SMD0402 | TA-I TECHNOLOGY CO., LTD | RM04JTN0 |  |  | PWA BOM |
|  | 610107A00-024-G |  |  | RES,0 Ohm,+/-5%,1/16W,G,SMD0402 | PANASONIC INDUSTRIAL CO.,LTD. | ERJ2GE0R00X |  |  | PWA BOM |
|  | 610107A00-029-G |  |  | RES,0 Ohm,+/-5%,1/16W,G,SMD0402 | VISHAY ENTER TECHNO LOGY.INC | CRCW04020000Z0ED |  |  | PWA BOM |
| 4 | 610118100-017-G | 0 | 2 | RES,1.4KOhm,+/-1%,1/16W,G,SMD0402 | KOA SPEER ELECTRONICS, INC. | RK73H1ETTP1401F | G | (+)R251,R252 | PWA BOM |
| 5 | 61011MV00-017-G | 0 | 24 | RES,510 Ohm,+/-1%,1/16W,G,SMD0402 | KOA SPEER ELECTRONICS, INC. | RK73H1ETTP5100F | G | (+)R1313,R1785,R1787,R1788,R1791,R1793,R1795,R1796,R1799,R1800,R1803,R1804,R1807,R1808,R1811,R1812,R1815,R1816,R1819,R1820,R1823,R1824,R1827,R1828 | PWA BOM |
| 6 | 61011FA00-017-G | 0 | 24 | RES,1.02KOhm,+/-1%,1/16W,G,SMD0402 | KOA SPEER ELECTRONICS, INC. | RK73H1ETTP1021F | G | (+)R1314,R1786,R1789,R1790,R1792,R1794,R1797,R1798,R1801,R1802,R1805,R1806,R1809,R1810,R1813,R1814,R1817,R1818,R1821,R1822,R1825,R1826,R1829,R1830 | PWA BOM |
| 7 | 61100AH00-017-G | 36 | 12 | RES,10KOhm,+/-0.5%,1/16W,G,SMD0402 | KOA SPEER ELECTRONICS, INC. | RN731ETTP1002D25 | G | (-)R1313,R1785,R1787,R1788,R1791,R1793,R1795,R1796,R1799,R1800,R1803,R1804,R1807,R1808,R1811,R1812,R1815,R1816,R1819,R1820,R1823,R1824,R1827,R1828 | PWA BOM |
|  | 61100AH00-012-G |  |  | RES,10KOhm,+/-0.5%,1/16W,G,SMD0402 | WALSIN TECHNOLOGY CORPORATION | WF04U1002DTL |  |  | PWA BOM |
|  | 61100AH00-011-G |  |  | RES,10KOhm,+/-0.5%,1/16W,G,SMD0402 | YAGEO CORPORATION COMPONENT | RT0402DRE0710KL |  |  | PWA BOM |
|  | 61100AH00-044-G |  |  | RES,10KOhm,+/-0.5%,1/16W,G,SMD0402 | TA-I TECHNOLOGY CO., LTD | RB04DTP1002 |  |  | PWA BOM |
| 8 | 3406B6F00-317-G | 0 | 1 | CONN,Header,WTB,2X3,R/A,Bla,2.5mm,15u,G,SMD-6 | MOLEX INCORPORATED | 15-91-2065 | G | (+)J_CPLD_JTAG | PWA BOM |
| 9 | 61010FG00-017-G | 24 | 0 | RES,20KOhm,+/-5%,1/16W,G,SMD0402 | KOA SPEER ELECTRONICS, INC. | RK73B1ETTP203J | G | (-)R1314,R1786,R1789,R1790,R1792,R1794,R1797,R1798,R1801,R1802,R1805,R1806,R1809,R1810,R1813,R1814,R1817,R1818,R1821,R1822,R1825,R1826,R1829,R1830 | PWA BOM |
|  | 61010FG00-012-G |  |  | RES,20KOhm,+/-5%,1/16W,G,SMD0402 | WALSIN TECHNOLOGY CORPORATION | WR04X203JTL |  |  | PWA BOM |
|  | 61010FG00-011-G |  |  | RES,20KOhm,+/-5%,1/16W,G,SMD0402 | YAGEO CORPORATION COMPONENT | RC0402JR-0720KL |  |  | PWA BOM |
| 10 | ZP91-0155C-1221 | 1 | 0 | CONN,Header,WTB,2X3,R/A,Bla,2.5mm,15u,G,SMD-6 | CENLINK | ZP91-0155C-1221 | G | (-)J_CPLD_JTAG | PWA BOM |
| OOOOOOOOOOOOOOOOOOOOOOOOOOOOOOOOOOOOOOOOOOOOOOOOOOOOOOOOOOOOOOOOOOOOOOOOOOOOOOOOOOOOOOOOOO | OOOOOOOOOOOOOOOOOOOOOOOOOOOOOOOOOOOOOOOOOOOOOOOOOOOOOOOOOOOOOOOOOOOOOOOOOOOOOOOOOOOOOOOOOO | OOOOOOOOOOOOOOOOOOOOOOOOOOOOOOOOOOOOOOOOOOOOOOOOOOOOOOOOOOOOOOOOOOOOOOOOOOOOOOOOOOOOOOOOOO | OOOOOOOOOOOOOOOOOOOOOOOOOOOOOOOOOOOOOOOOOOOOOOOOOOOOOOOOOOOOOOOOOOOOOOOOOOOOOOOOOOOOOOOOOO | OOOOOOOOOOOOOOOOOOOOOOOOOOOOOOOOOOOOOOOOOOOOOOOOOOOOOOOOOOOOOOOOOOOOOOOOOOOOOOOOOOOOOOOOOO | OOOOOOOOOOOOOOOOOOOOOOOOOOOOOOOOOOOOOOOOOOOOOOOOOOOOOOOOOOOOOOOOOOOOOOOOOOOOOOOOOOOOOOOOOO | OOOOOOOOOOOOOOOOOOOOOOOOOOOOOOOOOOOOOOOOOOOOOOOOOOOOOOOOOOOOOOOOOOOOOOOOOOOOOOOOOOOOOOOOOO | OOOOOOOOOOOOOOOOOOOOOOOOOOOOOOOOOOOOOOOOOOOOOOOOOOOOOOOOOOOOOOOOOOOOOOOOOOOOOOOOOOOOOOOOOO | OOOOOOOOOOOOOOOOOOOOOOOOOOOOOOOOOOOOOOOOOOOOOOOOOOOOOOOOOOOOOOOOOOOOOOOOOOOOOOOOOOOOOOOOOO |  |
| TLA Parts Change |  |  |  |  |  |  |  |  |  |
| Item | Foxconn P/N | Qty | Part Description | Manufacturer Full Name | Manufacturer P/N | RoHS | Location | Remark |  |
| BOM Change List Date:Fri Sep 08 17:16:06 GMT+08:00 2017 |  |  |  |  |  |  |  |  |  |
| New BOM file : E:\barreleye g2\0905\BPX24 EXPANDER\BPX24 0906 .xls |  |  |  |  |  |  |  |  |  |
| Old BOM file : E:\barreleye g2\0905\BPX24 EXPANDER\BPX24 0831 .xls |  |  |  |  |  |  |  |  |  |
| ##### Add Parts |  |  |  |  |  |  |  |  |  |
| Item | Location | Qty | Foxconn P/N | Part Description | Manufacturer Full Name | Manufacturer P/N | RoHS | Sheet |  |
| ##### Remove Parts |  |  |  |  |  |  |  |  |  |
| Item | Location | Qty | Foxconn P/N | Part Description | Manufacturer Full Name | Manufacturer P/N | RoHS | Sheet |  |
| ##### Change Parts |  |  |  |  |  |  |  |  |  |
| Item | Location | Qty | Foxconn P/N | Part Description | Manufacturer Full Name | Manufacturer P/N | RoHS | Sheet | Remark |
| 1 | PSTR5,PFTR5,PETR5 | 3 | 61100QD00-017-G | RES,787 Ohm,+/-0.1%,1/16W,G,SMD0402 | KOA SPEER ELECTRONICS, INC. | RN731ETTP7870B25 | G | PWA BOM | In New BOM |
|  |  |  | 61100QD00-011-G | RES,787 Ohm,+/-0.1%,1/16W,G,SMD0402 | YAGEO CORPORATION COMPONENT | RT0402BRD07787RL | G | PWA BOM | In New BOM |
|  |  |  | 61100QD00-044-G | RES,787 Ohm,+/-0.1%,1/16W,G,SMD0402 | TA-I TECHNOLOGY CO., LTD | RB04BTP7870 | G | PWA BOM | In New BOM |
|  |  |  | 61100QD00-012-G | RES,787 Ohm,+/-0.1%,1/16W,G,SMD0402 | WALSIN TECHNOLOGY CORPORATION | WF04U7870BTL | G | PWA BOM | In New BOM |
|  | PSTR5,PFTR5,PETR5 | 3 | 61100QD00-017-G | RES,787 Ohm,+/-0.1%,1/16W,G,SMD0402 | KOA SPEER ELECTRONICS, INC. | RN731ETTP7870B25 | G | PWA BOM | In Old BOM |
|  |  |  | 61100QD00-012-G | RES,787 Ohm,+/-0.1%,1/16W,G,SMD0402 | WALSIN TECHNOLOGY CORPORATION | WF04U7870BTL | G | PWA BOM | In Old BOM |
|  |  |  | 61100QD00-011-G | RES,787 Ohm,+/-0.1%,1/16W,G,SMD0402 | YAGEO CORPORATION COMPONENT | RT0402BRD07787RL | G | PWA BOM | In Old BOM |
| 2 | PSTR6,PFTR6,PETR6 | 3 | 61100SU00-017-G | RES,105 Ohm,+/-0.1%,1/16W,G,SMD0402 | KOA SPEER ELECTRONICS, INC. | RN731ETTP1050B25 | G | PWA BOM | In New BOM |
|  |  |  | 61100SU00-011-G | RES,105 Ohm,+/-0.1%,1/16W,G,SMD0402 | YAGEO CORPORATION COMPONENT | RT0402BRD07105RL | G | PWA BOM | In New BOM |
|  |  |  | 61100SU00-044-G | RES,105 Ohm,+/-0.1%,1/16W,G,SMD0402 | TA-I TECHNOLOGY CO., LTD | RB04BTP1050 | G | PWA BOM | In New BOM |
|  |  |  | 61100SU00-012-G | RES,105 Ohm,+/-0.1%,1/16W,G,SMD0402 | WALSIN TECHNOLOGY CORPORATION | WF04U1050BTL | G | PWA BOM | In New BOM |
|  | PSTR6,PFTR6,PETR6 | 3 | 61100SU00-017-G | RES,105 Ohm,+/-0.1%,1/16W,G,SMD0402 | KOA SPEER ELECTRONICS, INC. | RN731ETTP1050B25 | G | PWA BOM | In Old BOM |
|  |  |  | 61100SU00-012-G | RES,105 Ohm,+/-0.1%,1/16W,G,SMD0402 | WALSIN TECHNOLOGY CORPORATION | WF04U1050BTL | G | PWA BOM | In Old BOM |
|  |  |  | 61100SU00-011-G | RES,105 Ohm,+/-0.1%,1/16W,G,SMD0402 | YAGEO CORPORATION COMPONENT | RT0402BRD07105RL | G | PWA BOM | In Old BOM |
| 3 | R251,R252 | 2 | 610118100-017-G | RES,1.4KOhm,+/-1%,1/16W,G,SMD0402 | KOA SPEER ELECTRONICS, INC. | RK73H1ETTP1401F | G | PWA BOM | In New BOM |
|  |  |  | 610118100-012-G | RES,1.4KOhm,+/-1%,1/16W,G,SMD0402 | WALSIN TECHNOLOGY CORPORATION | WR04X1401FTL | G | PWA BOM | In New BOM |
|  |  |  | 610118100-011-G | RES,1.4KOhm,+/-1%,1/16W,G,SMD0402 | YAGEO CORPORATION COMPONENT | RC0402FR-071K4L | G | PWA BOM | In New BOM |
|  |  |  | 610118100-044-G | RES,1.4KOhm,+/-1%,1/16W,G,SMD0402 | TA-I TECHNOLOGY CO., LTD | RM04FTN1401 | G | PWA BOM | In New BOM |
|  |  |  | 610118100-024-G | RES,1.4KOhm,+/-1%,1/16W,G,SMD0402 | PANASONIC INDUSTRIAL CO.,LTD. | ERJ2RKF1401X | G | PWA BOM | In New BOM |
|  | R251,R252 | 2 | 610118100-017-G | RES,1.4KOhm,+/-1%,1/16W,G,SMD0402 | KOA SPEER ELECTRONICS, INC. | RK73H1ETTP1401F | G | PWA BOM | In Old BOM |
|  |  |  | 610118100-012-G | RES,1.4KOhm,+/-1%,1/16W,G,SMD0402 | WALSIN TECHNOLOGY CORPORATION | WR04X1401FTL |  | PWA BOM | In Old BOM |
|  |  |  | 610118100-011-G | RES,1.4KOhm,+/-1%,1/16W,G,SMD0402 | YAGEO CORPORATION COMPONENT | RC0402FR-071K4L |  | PWA BOM | In Old BOM |
|  |  |  | 610118100-044-G | RES,1.4KOhm,+/-1%,1/16W,G,SMD0402 | TA-I TECHNOLOGY CO., LTD | RM04FTN1401 |  | PWA BOM | In Old BOM |
| 4 | C2231 | 1 | 620109S00-023-G | CAP,4.7uF,+/-10%,X7R,10V,G,SMD0805 | TAIYO ELECTRIC IND.CO.LTD | LMK212B7475KG-T | G | PWA BOM | In New BOM |
|  |  |  | 620109S00-026-G | CAP,4.7uF,+/-10%,X7R,10V,G,SMD0805 | SAMSUNG SEMICONDUCTOR | CL21B475KPFNNNE | G | PWA BOM | In New BOM |
|  |  |  | 620109S00-015-G | CAP,4.7uF,+/-10%,X7R,10V,G,SMD0805 | MURATA ELEC. NORTH AMERICA | GRM21BR71A475K | G | PWA BOM | In New BOM |
|  | C2231 | 1 | 620109S00-015-G | CAP,4.7uF,+/-10%,X7R,10V,G,SMD0805 | MURATA ELEC. NORTH AMERICA | GRM21BR71A475K | G | PWA BOM | In Old BOM |
|  |  |  | 620109S00-023-G | CAP,4.7uF,+/-10%,X7R,10V,G,SMD0805 | TAIYO ELECTRIC IND.CO.LTD | LMK212B7475KG-T | G | PWA BOM | In Old BOM |
|  |  |  | 620109S00-026-G | CAP,4.7uF,+/-10%,X7R,10V,G,SMD0805 | SAMSUNG SEMICONDUCTOR | CL21B475KPFNNNE | G | PWA BOM | In Old BOM |
| ##### Change Revision |  |  |  |  |  |  |  |  |  |
| Sheet | REV OF BOM | CUSTOMER | CUSTOMER P/N | PWA PN | PWA DESCRIPTION | PWA REV | DATE | Remark |  |
| OOOOOOOOOOOOOOOOOOOOOOOOOOOOOOOOOOOOOOOOOOOOOOOOOOOOOOOOOOOOOOOOOOOOOOOOOOOOOOOOOOOOOOOOOO | OOOOOOOOOOOOOOOOOOOOOOOOOOOOOOOOOOOOOOOOOOOOOOOOOOOOOOOOOOOOOOOOOOOOOOOOOOOOOOOOOOOOOOOOOO | OOOOOOOOOOOOOOOOOOOOOOOOOOOOOOOOOOOOOOOOOOOOOOOOOOOOOOOOOOOOOOOOOOOOOOOOOOOOOOOOOOOOOOOOOO | OOOOOOOOOOOOOOOOOOOOOOOOOOOOOOOOOOOOOOOOOOOOOOOOOOOOOOOOOOOOOOOOOOOOOOOOOOOOOOOOOOOOOOOOOO | OOOOOOOOOOOOOOOOOOOOOOOOOOOOOOOOOOOOOOOOOOOOOOOOOOOOOOOOOOOOOOOOOOOOOOOOOOOOOOOOOOOOOOOOOO | OOOOOOOOOOOOOOOOOOOOOOOOOOOOOOOOOOOOOOOOOOOOOOOOOOOOOOOOOOOOOOOOOOOOOOOOOOOOOOOOOOOOOOOOOO | OOOOOOOOOOOOOOOOOOOOOOOOOOOOOOOOOOOOOOOOOOOOOOOOOOOOOOOOOOOOOOOOOOOOOOOOOOOOOOOOOOOOOOOOOO | OOOOOOOOOOOOOOOOOOOOOOOOOOOOOOOOOOOOOOOOOOOOOOOOOOOOOOOOOOOOOOOOOOOOOOOOOOOOOOOOOOOOOOOOOO | OOOOOOOOOOOOOOOOOOOOOOOOOOOOOOOOOOOOOOOOOOOOOOOOOOOOOOOOOOOOOOOOOOOOOOOOOOOOOOOOOOOOOOOOOO | OOOOOOOOOOOOOOOOOOOOOOOOOOOOOOOOOOOOOOOOOOOOOOOOOOOOOOOOOOOOOOOOOOOOOOOOOOOOOOOOOOOOOOOOOO |
| Second Source Change |  |  |  |  |  |  |  |  |  |
| Item | Location | Change Type | Foxconn P/N | Part Description | Manufacturer Full Name | Manufacturer P/N | RoHS | Sheet |  |
| 1 | PSTR5,PFTR5,PETR5 |  | 61100QD00-017-G | RES,787 Ohm,+/-0.1%,1/16W,G,SMD0402 | KOA SPEER ELECTRONICS, INC. | RN731ETTP7870B25 | G | PWA BOM |  |
|  |  | NO | 61100QD00-011-G | RES,787 Ohm,+/-0.1%,1/16W,G,SMD0402 | YAGEO CORPORATION COMPONENT | RT0402BRD07787RL | G | PWA BOM |  |
|  |  | ADD | 61100QD00-044-G | RES,787 Ohm,+/-0.1%,1/16W,G,SMD0402 | TA-I TECHNOLOGY CO., LTD | RB04BTP7870 | G | PWA BOM |  |
|  |  | NO | 61100QD00-012-G | RES,787 Ohm,+/-0.1%,1/16W,G,SMD0402 | WALSIN TECHNOLOGY CORPORATION | WF04U7870BTL | G | PWA BOM |  |
| 2 | PSTR6,PFTR6,PETR6 |  | 61100SU00-017-G | RES,105 Ohm,+/-0.1%,1/16W,G,SMD0402 | KOA SPEER ELECTRONICS, INC. | RN731ETTP1050B25 | G | PWA BOM |  |
|  |  | NO | 61100SU00-011-G | RES,105 Ohm,+/-0.1%,1/16W,G,SMD0402 | YAGEO CORPORATION COMPONENT | RT0402BRD07105RL | G | PWA BOM |  |
|  |  | ADD | 61100SU00-044-G | RES,105 Ohm,+/-0.1%,1/16W,G,SMD0402 | TA-I TECHNOLOGY CO., LTD | RB04BTP1050 | G | PWA BOM |  |
|  |  | NO | 61100SU00-012-G | RES,105 Ohm,+/-0.1%,1/16W,G,SMD0402 | WALSIN TECHNOLOGY CORPORATION | WF04U1050BTL | G | PWA BOM |  |
| 3 | R251,R252 |  | 610118100-017-G | RES,1.4KOhm,+/-1%,1/16W,G,SMD0402 | KOA SPEER ELECTRONICS, INC. | RK73H1ETTP1401F | G | PWA BOM |  |
|  |  | NO | 610118100-012-G | RES,1.4KOhm,+/-1%,1/16W,G,SMD0402 | WALSIN TECHNOLOGY CORPORATION | WR04X1401FTL | G | PWA BOM |  |
|  |  | NO | 610118100-011-G | RES,1.4KOhm,+/-1%,1/16W,G,SMD0402 | YAGEO CORPORATION COMPONENT | RC0402FR-071K4L | G | PWA BOM |  |
|  |  | NO | 610118100-044-G | RES,1.4KOhm,+/-1%,1/16W,G,SMD0402 | TA-I TECHNOLOGY CO., LTD | RM04FTN1401 | G | PWA BOM |  |
|  |  | ADD | 610118100-024-G | RES,1.4KOhm,+/-1%,1/16W,G,SMD0402 | PANASONIC INDUSTRIAL CO.,LTD. | ERJ2RKF1401X | G | PWA BOM |  |
| OOOOOOOOOOOOOOOOOOOOOOOOOOOOOOOOOOOOOOOOOOOOOOOOOOOOOOOOOOOOOOOOOOOOOOOOOOOOOOOOOOOOOOOOOO | OOOOOOOOOOOOOOOOOOOOOOOOOOOOOOOOOOOOOOOOOOOOOOOOOOOOOOOOOOOOOOOOOOOOOOOOOOOOOOOOOOOOOOOOOO | OOOOOOOOOOOOOOOOOOOOOOOOOOOOOOOOOOOOOOOOOOOOOOOOOOOOOOOOOOOOOOOOOOOOOOOOOOOOOOOOOOOOOOOOOO | OOOOOOOOOOOOOOOOOOOOOOOOOOOOOOOOOOOOOOOOOOOOOOOOOOOOOOOOOOOOOOOOOOOOOOOOOOOOOOOOOOOOOOOOOO | OOOOOOOOOOOOOOOOOOOOOOOOOOOOOOOOOOOOOOOOOOOOOOOOOOOOOOOOOOOOOOOOOOOOOOOOOOOOOOOOOOOOOOOOOO | OOOOOOOOOOOOOOOOOOOOOOOOOOOOOOOOOOOOOOOOOOOOOOOOOOOOOOOOOOOOOOOOOOOOOOOOOOOOOOOOOOOOOOOOOO | OOOOOOOOOOOOOOOOOOOOOOOOOOOOOOOOOOOOOOOOOOOOOOOOOOOOOOOOOOOOOOOOOOOOOOOOOOOOOOOOOOOOOOOOOO | OOOOOOOOOOOOOOOOOOOOOOOOOOOOOOOOOOOOOOOOOOOOOOOOOOOOOOOOOOOOOOOOOOOOOOOOOOOOOOOOOOOOOOOOOO | OOOOOOOOOOOOOOOOOOOOOOOOOOOOOOOOOOOOOOOOOOOOOOOOOOOOOOOOOOOOOOOOOOOOOOOOOOOOOOOOOOOOOOOOOO | OOOOOOOOOOOOOOOOOOOOOOOOOOOOOOOOOOOOOOOOOOOOOOOOOOOOOOOOOOOOOOOOOOOOOOOOOOOOOOOOOOOOOOOOOO |
| Master Materials Change |  |  |  |  |  |  |  |  |  |
| Item | Foxconn P/N | Orig._Usage | New_Usage | Part Description | Manufacturer Full Name | Manufacturer P/N | RoHS | Location | Sheet |
| 1 | 620109S00-023-G | 0 | 1 | CAP,4.7uF,+/-10%,X7R,10V,G,SMD0805 | TAIYO ELECTRIC IND.CO.LTD | LMK212B7475KG-T | G | (+)C2231 | PWA BOM |
|  | 620109S00-026-G |  |  | CAP,4.7uF,+/-10%,X7R,10V,G,SMD0805 | SAMSUNG SEMICONDUCTOR | CL21B475KPFNNNE |  |  | PWA BOM |
|  | 620109S00-015-G |  |  | CAP,4.7uF,+/-10%,X7R,10V,G,SMD0805 | MURATA ELEC. NORTH AMERICA | GRM21BR71A475K |  |  | PWA BOM |
| 2 | 620109S00-015-G | 1 | 0 | CAP,4.7uF,+/-10%,X7R,10V,G,SMD0805 | MURATA ELEC. NORTH AMERICA | GRM21BR71A475K | G | (-)C2231 | PWA BOM |
|  | 620109S00-023-G |  |  | CAP,4.7uF,+/-10%,X7R,10V,G,SMD0805 | TAIYO ELECTRIC IND.CO.LTD | LMK212B7475KG-T |  |  | PWA BOM |
|  | 620109S00-026-G |  |  | CAP,4.7uF,+/-10%,X7R,10V,G,SMD0805 | SAMSUNG SEMICONDUCTOR | CL21B475KPFNNNE |  |  | PWA BOM |
| OOOOOOOOOOOOOOOOOOOOOOOOOOOOOOOOOOOOOOOOOOOOOOOOOOOOOOOOOOOOOOOOOOOOOOOOOOOOOOOOOOOOOOOOOO | OOOOOOOOOOOOOOOOOOOOOOOOOOOOOOOOOOOOOOOOOOOOOOOOOOOOOOOOOOOOOOOOOOOOOOOOOOOOOOOOOOOOOOOOOO | OOOOOOOOOOOOOOOOOOOOOOOOOOOOOOOOOOOOOOOOOOOOOOOOOOOOOOOOOOOOOOOOOOOOOOOOOOOOOOOOOOOOOOOOOO | OOOOOOOOOOOOOOOOOOOOOOOOOOOOOOOOOOOOOOOOOOOOOOOOOOOOOOOOOOOOOOOOOOOOOOOOOOOOOOOOOOOOOOOOOO | OOOOOOOOOOOOOOOOOOOOOOOOOOOOOOOOOOOOOOOOOOOOOOOOOOOOOOOOOOOOOOOOOOOOOOOOOOOOOOOOOOOOOOOOOO | OOOOOOOOOOOOOOOOOOOOOOOOOOOOOOOOOOOOOOOOOOOOOOOOOOOOOOOOOOOOOOOOOOOOOOOOOOOOOOOOOOOOOOOOOO | OOOOOOOOOOOOOOOOOOOOOOOOOOOOOOOOOOOOOOOOOOOOOOOOOOOOOOOOOOOOOOOOOOOOOOOOOOOOOOOOOOOOOOOOOO | OOOOOOOOOOOOOOOOOOOOOOOOOOOOOOOOOOOOOOOOOOOOOOOOOOOOOOOOOOOOOOOOOOOOOOOOOOOOOOOOOOOOOOOOOO | OOOOOOOOOOOOOOOOOOOOOOOOOOOOOOOOOOOOOOOOOOOOOOOOOOOOOOOOOOOOOOOOOOOOOOOOOOOOOOOOOOOOOOOOOO | OOOOOOOOOOOOOOOOOOOOOOOOOOOOOOOOOOOOOOOOOOOOOOOOOOOOOOOOOOOOOOOOOOOOOOOOOOOOOOOOOOOOOOOOOO |
| TLA Parts Change |  |  |  |  |  |  |  |  |  |
| Item | Foxconn P/N | Qty | Part Description | Manufacturer Full Name | Manufacturer P/N | RoHS | Location | Remark | BOM |
| BOM Change List Date:Tue Sep 12 17:59:51 GMT+08:00 2017 |  |  |  |  |  |  |  |  |  |
| New BOM file : E:\barreleye g2\0912\BPX24 EXPANDER\Barreleye-G2_Tri-mode BPX24-DVT-X01-BOM-X06-20170912.xls |  |  |  |  |  |  |  |  |  |
| Old BOM file : E:\barreleye g2\0912\BPX24 EXPANDER\BPX24 0906.xls |  |  |  |  |  |  |  |  |  |
| ##### Add Parts |  |  |  |  |  |  |  |  |  |
| Item | Location | Qty | Foxconn P/N | Part Description | Manufacturer Full Name | Manufacturer P/N | RoHS | Sheet |  |
| ##### Remove Parts |  |  |  |  |  |  |  |  |  |
| Item | Location | Qty | Foxconn P/N | Part Description | Manufacturer Full Name | Manufacturer P/N | RoHS | Sheet |  |
| ##### Change Parts |  |  |  |  |  |  |  |  |  |
| Item | Location | Qty | Foxconn P/N | Part Description | Manufacturer Full Name | Manufacturer P/N | RoHS | Sheet | Remark |
| 1 | R1314,R1786,R1789,R1790,R1792,R1794,R1797,R1798,R1801,R1802,R1805,R1806,R1809,R1810,R1813,R1814,R1817,R1818,R1821,R1822,R1825,R1826,R1829,R1830 | 24 | 610100T00-017-G | RES,1KOhm,+/-5%,1/16W,G,SMD0402 | KOA SPEER ELECTRONICS, INC. | RK73B1ETTP102J | G | PWA BOM | In New BOM |
|  |  |  | 610100T00-012-G | RES,1KOhm,+/-5%,1/16W,G,SMD0402 | WALSIN TECHNOLOGY CORPORATION | WR04X102JTL | G | PWA BOM | In New BOM |
|  |  |  | 610100T00-011-G | RES,1KOhm,+/-5%,1/16W,G,SMD0402 | YAGEO CORPORATION COMPONENT | RC0402JR-071KL | G | PWA BOM | In New BOM |
|  |  |  | 610100T00-044-G | RES,1KOhm,+/-5%,1/16W,G,SMD0402 | TA-I TECHNOLOGY CO., LTD | RM04JTN102 | G | PWA BOM | In New BOM |
|  |  |  | 610100T00-024-G | RES,1KOhm,+/-5%,1/16W,G,SMD0402 | PANASONIC INDUSTRIAL CO.,LTD. | ERJ2GEJ102X | G | PWA BOM | In New BOM |
|  | R1314,R1786,R1789,R1790,R1792,R1794,R1797,R1798,R1801,R1802,R1805,R1806,R1809,R1810,R1813,R1814,R1817,R1818,R1821,R1822,R1825,R1826,R1829,R1830 | 24 | 61011FA00-017-G | RES,1.02KOhm,+/-1%,1/16W,G,SMD0402 | KOA SPEER ELECTRONICS, INC. | RK73H1ETTP1021F | G | PWA BOM | In Old BOM |
|  |  |  | 61011FA00-011-G | RES,1.02KOhm,+/-1%,1/16W,G,SMD0402 | YAGEO CORPORATION COMPONENT | RC0402FR-071K02L | G | PWA BOM | In Old BOM |
|  |  |  | 61011FA00-012-G | RES,1.02KOhm,+/-1%,1/16W,G,SMD0402 | WALSIN TECHNOLOGY CORPORATION | WR04X1021FTL | G | PWA BOM | In Old BOM |
|  |  |  | 61011FA00-044-G | RES,1.02KOhm,+/-1%,1/16W,G,SMD0402 | TA-I TECHNOLOGY CO., LTD | RM04FTN1021 | G | PWA BOM | In Old BOM |
| 2 | J_CPLD_JTAG | 1 | 3406B6F00-317-G | CONN,Header,WTB,2X3,R/A,Bla,2.5mm,15u,G,SMD-6 | MOLEX INCORPORATED | 15-91-2065 | G | PWA BOM | In New BOM |
|  | J_CPLD_JTAG | 1 | ZP91-0155C-1221 | CONN,Header,WTB,2X3,R/A,Bla,2.5mm,15u,G,SMD-6 | CENLINK | ZP91-0155C-1221 | G | PWA BOM | In Old BOM |
| ##### Change Revision |  |  |  |  |  |  |  |  |  |
| Sheet | REV OF BOM | CUSTOMER | CUSTOMER P/N | PWA PN | PWA DESCRIPTION | PWA REV | DATE | Remark |  |
| OOOOOOOOOOOOOOOOOOOOOOOOOOOOOOOOOOOOOOOOOOOOOOOOOOOOOOOOOOOOOOOOOOOOOOOOOOOOOOOOOOOOOOOOOO | OOOOOOOOOOOOOOOOOOOOOOOOOOOOOOOOOOOOOOOOOOOOOOOOOOOOOOOOOOOOOOOOOOOOOOOOOOOOOOOOOOOOOOOOOO | OOOOOOOOOOOOOOOOOOOOOOOOOOOOOOOOOOOOOOOOOOOOOOOOOOOOOOOOOOOOOOOOOOOOOOOOOOOOOOOOOOOOOOOOOO | OOOOOOOOOOOOOOOOOOOOOOOOOOOOOOOOOOOOOOOOOOOOOOOOOOOOOOOOOOOOOOOOOOOOOOOOOOOOOOOOOOOOOOOOOO | OOOOOOOOOOOOOOOOOOOOOOOOOOOOOOOOOOOOOOOOOOOOOOOOOOOOOOOOOOOOOOOOOOOOOOOOOOOOOOOOOOOOOOOOOO | OOOOOOOOOOOOOOOOOOOOOOOOOOOOOOOOOOOOOOOOOOOOOOOOOOOOOOOOOOOOOOOOOOOOOOOOOOOOOOOOOOOOOOOOOO | OOOOOOOOOOOOOOOOOOOOOOOOOOOOOOOOOOOOOOOOOOOOOOOOOOOOOOOOOOOOOOOOOOOOOOOOOOOOOOOOOOOOOOOOOO | OOOOOOOOOOOOOOOOOOOOOOOOOOOOOOOOOOOOOOOOOOOOOOOOOOOOOOOOOOOOOOOOOOOOOOOOOOOOOOOOOOOOOOOOOO | OOOOOOOOOOOOOOOOOOOOOOOOOOOOOOOOOOOOOOOOOOOOOOOOOOOOOOOOOOOOOOOOOOOOOOOOOOOOOOOOOOOOOOOOOO | OOOOOOOOOOOOOOOOOOOOOOOOOOOOOOOOOOOOOOOOOOOOOOOOOOOOOOOOOOOOOOOOOOOOOOOOOOOOOOOOOOOOOOOOOO |
| Second Source Change |  |  |  |  |  |  |  |  |  |
| Item | Location | Change Type | Foxconn P/N | Part Description | Manufacturer Full Name | Manufacturer P/N | RoHS | Sheet |  |
| OOOOOOOOOOOOOOOOOOOOOOOOOOOOOOOOOOOOOOOOOOOOOOOOOOOOOOOOOOOOOOOOOOOOOOOOOOOOOOOOOOOOOOOOOO | OOOOOOOOOOOOOOOOOOOOOOOOOOOOOOOOOOOOOOOOOOOOOOOOOOOOOOOOOOOOOOOOOOOOOOOOOOOOOOOOOOOOOOOOOO | OOOOOOOOOOOOOOOOOOOOOOOOOOOOOOOOOOOOOOOOOOOOOOOOOOOOOOOOOOOOOOOOOOOOOOOOOOOOOOOOOOOOOOOOOO | OOOOOOOOOOOOOOOOOOOOOOOOOOOOOOOOOOOOOOOOOOOOOOOOOOOOOOOOOOOOOOOOOOOOOOOOOOOOOOOOOOOOOOOOOO | OOOOOOOOOOOOOOOOOOOOOOOOOOOOOOOOOOOOOOOOOOOOOOOOOOOOOOOOOOOOOOOOOOOOOOOOOOOOOOOOOOOOOOOOOO | OOOOOOOOOOOOOOOOOOOOOOOOOOOOOOOOOOOOOOOOOOOOOOOOOOOOOOOOOOOOOOOOOOOOOOOOOOOOOOOOOOOOOOOOOO | OOOOOOOOOOOOOOOOOOOOOOOOOOOOOOOOOOOOOOOOOOOOOOOOOOOOOOOOOOOOOOOOOOOOOOOOOOOOOOOOOOOOOOOOOO | OOOOOOOOOOOOOOOOOOOOOOOOOOOOOOOOOOOOOOOOOOOOOOOOOOOOOOOOOOOOOOOOOOOOOOOOOOOOOOOOOOOOOOOOOO | OOOOOOOOOOOOOOOOOOOOOOOOOOOOOOOOOOOOOOOOOOOOOOOOOOOOOOOOOOOOOOOOOOOOOOOOOOOOOOOOOOOOOOOOOO | OOOOOOOOOOOOOOOOOOOOOOOOOOOOOOOOOOOOOOOOOOOOOOOOOOOOOOOOOOOOOOOOOOOOOOOOOOOOOOOOOOOOOOOOOO |
| Master Materials Change |  |  |  |  |  |  |  |  |  |
| Item | Foxconn P/N | Orig._Usage | New_Usage | Part Description | Manufacturer Full Name | Manufacturer P/N | RoHS | Location | Sheet |
| 1 | 610100T00-017-G | 17 | 41 | RES,1KOhm,+/-5%,1/16W,G,SMD0402 | KOA SPEER ELECTRONICS, INC. | RK73B1ETTP102J | G | (+)R1314,R1786,R1789,R1790,R1792,R1794,R1797,R1798,R1801,R1802,R1805,R1806,R1809,R1810,R1813,R1814,R1817,R1818,R1821,R1822,R1825,R1826,R1829,R1830 | PWA BOM |
|  | 610100T00-012-G |  |  | RES,1KOhm,+/-5%,1/16W,G,SMD0402 | WALSIN TECHNOLOGY CORPORATION | WR04X102JTL |  |  | PWA BOM |
|  | 610100T00-011-G |  |  | RES,1KOhm,+/-5%,1/16W,G,SMD0402 | YAGEO CORPORATION COMPONENT | RC0402JR-071KL |  |  | PWA BOM |
|  | 610100T00-044-G |  |  | RES,1KOhm,+/-5%,1/16W,G,SMD0402 | TA-I TECHNOLOGY CO., LTD | RM04JTN102 |  |  | PWA BOM |
|  | 610100T00-024-G |  |  | RES,1KOhm,+/-5%,1/16W,G,SMD0402 | PANASONIC INDUSTRIAL CO.,LTD. | ERJ2GEJ102X |  |  | PWA BOM |
| 2 | 3406B6F00-317-G | 0 | 1 | CONN,Header,WTB,2X3,R/A,Bla,2.5mm,15u,G,SMD-6 | MOLEX INCORPORATED | 15-91-2065 | G | (+)J_CPLD_JTAG | PWA BOM |
| 3 | 61011FA00-017-G | 24 | 0 | RES,1.02KOhm,+/-1%,1/16W,G,SMD0402 | KOA SPEER ELECTRONICS, INC. | RK73H1ETTP1021F | G | (-)R1314,R1786,R1789,R1790,R1792,R1794,R1797,R1798,R1801,R1802,R1805,R1806,R1809,R1810,R1813,R1814,R1817,R1818,R1821,R1822,R1825,R1826,R1829,R1830 | PWA BOM |
|  | 61011FA00-011-G |  |  | RES,1.02KOhm,+/-1%,1/16W,G,SMD0402 | YAGEO CORPORATION COMPONENT | RC0402FR-071K02L |  |  | PWA BOM |
|  | 61011FA00-012-G |  |  | RES,1.02KOhm,+/-1%,1/16W,G,SMD0402 | WALSIN TECHNOLOGY CORPORATION | WR04X1021FTL |  |  | PWA BOM |
|  | 61011FA00-044-G |  |  | RES,1.02KOhm,+/-1%,1/16W,G,SMD0402 | TA-I TECHNOLOGY CO., LTD | RM04FTN1021 |  |  | PWA BOM |
| 4 | ZP91-0155C-1221 | 1 | 0 | CONN,Header,WTB,2X3,R/A,Bla,2.5mm,15u,G,SMD-6 | CENLINK | ZP91-0155C-1221 | G | (-)J_CPLD_JTAG | PWA BOM |
| OOOOOOOOOOOOOOOOOOOOOOOOOOOOOOOOOOOOOOOOOOOOOOOOOOOOOOOOOOOOOOOOOOOOOOOOOOOOOOOOOOOOOOOOOO | OOOOOOOOOOOOOOOOOOOOOOOOOOOOOOOOOOOOOOOOOOOOOOOOOOOOOOOOOOOOOOOOOOOOOOOOOOOOOOOOOOOOOOOOOO | OOOOOOOOOOOOOOOOOOOOOOOOOOOOOOOOOOOOOOOOOOOOOOOOOOOOOOOOOOOOOOOOOOOOOOOOOOOOOOOOOOOOOOOOOO | OOOOOOOOOOOOOOOOOOOOOOOOOOOOOOOOOOOOOOOOOOOOOOOOOOOOOOOOOOOOOOOOOOOOOOOOOOOOOOOOOOOOOOOOOO | OOOOOOOOOOOOOOOOOOOOOOOOOOOOOOOOOOOOOOOOOOOOOOOOOOOOOOOOOOOOOOOOOOOOOOOOOOOOOOOOOOOOOOOOOO | OOOOOOOOOOOOOOOOOOOOOOOOOOOOOOOOOOOOOOOOOOOOOOOOOOOOOOOOOOOOOOOOOOOOOOOOOOOOOOOOOOOOOOOOOO | OOOOOOOOOOOOOOOOOOOOOOOOOOOOOOOOOOOOOOOOOOOOOOOOOOOOOOOOOOOOOOOOOOOOOOOOOOOOOOOOOOOOOOOOOO | OOOOOOOOOOOOOOOOOOOOOOOOOOOOOOOOOOOOOOOOOOOOOOOOOOOOOOOOOOOOOOOOOOOOOOOOOOOOOOOOOOOOOOOOOO | OOOOOOOOOOOOOOOOOOOOOOOOOOOOOOOOOOOOOOOOOOOOOOOOOOOOOOOOOOOOOOOOOOOOOOOOOOOOOOOOOOOOOOOOOO |  |
| TLA Parts Change |  |  |  |  |  |  |  |  |  |
| Item | Foxconn P/N | Qty | Part Description | Manufacturer Full Name | Manufacturer P/N | RoHS | Location | Remark |  |
| BOM Change List Date:Thu Sep 14 13:43:02 GMT+08:00 2017 |  |  |  |  |  |  |  |  |  |
| New BOM file : E:\barreleye g2\0913\foxbis\BPX24 13.xls |  |  |  |  |  |  |  |  |  |
| Old BOM file : E:\barreleye g2\0913\foxbis\BPX24 12.xls |  |  |  |  |  |  |  |  |  |
| ##### Add Parts |  |  |  |  |  |  |  |  |  |
| Item | Location | Qty | Foxconn P/N | Part Description | Manufacturer Full Name | Manufacturer P/N | RoHS | Sheet |  |
| ##### Remove Parts |  |  |  |  |  |  |  |  |  |
| Item | Location | Qty | Foxconn P/N | Part Description | Manufacturer Full Name | Manufacturer P/N | RoHS | Sheet |  |
| ##### Change Parts |  |  |  |  |  |  |  |  |  |
| Item | Location | Qty | Foxconn P/N | Part Description | Manufacturer Full Name | Manufacturer P/N | RoHS | Sheet | Remark |
| 1 | U_BP_FRU1 | 1 | 41040HW00-191-G | EEPROM,AT24C02D-SSHM-T,1.7~3.6V,2K,I2C,G,SOIC-8,SMD | ATMEL CORPORATION | AT24C02D-SSHM-T | G | PWA BOM | In New BOM |
|  |  |  | 410401W00-214-G | EEPROM,M24C02-WMN6TP,2.5~5.5V,256*8,I2C,G,SOIC-8,SMD | ST MICRO ELECTRONICS,INC | M24C02-WMN6TP |  | PWA BOM | In New BOM |
|  |  |  | 41040J500-232-G | EEPROM,24AA024T-I/SN,1.7V~5.5V,2K,I2C,G,SOIC-8,SMD | MICROCHIP TECHNOLOGY INC | 24AA024T-I/SN |  | PWA BOM | In New BOM |
|  | U_BP_FRU1 | 1 | 41040B600-191-G | EEPROM,AT24C02C-SSHM-T,1.7~5.5V,2K,I2C,G,SOIC-8,SMD | ATMEL CORPORATION | AT24C02C-SSHM-T | G | PWA BOM | In Old BOM |
| ##### Change Revision |  |  |  |  |  |  |  |  |  |
| Sheet | REV OF BOM | CUSTOMER | CUSTOMER P/N | PWA PN | PWA DESCRIPTION | PWA REV | DATE | Remark |  |
| OOOOOOOOOOOOOOOOOOOOOOOOOOOOOOOOOOOOOOOOOOOOOOOOOOOOOOOOOOOOOOOOOOOOOOOOOOOOOOOOOOOOOOOOOO | OOOOOOOOOOOOOOOOOOOOOOOOOOOOOOOOOOOOOOOOOOOOOOOOOOOOOOOOOOOOOOOOOOOOOOOOOOOOOOOOOOOOOOOOOO | OOOOOOOOOOOOOOOOOOOOOOOOOOOOOOOOOOOOOOOOOOOOOOOOOOOOOOOOOOOOOOOOOOOOOOOOOOOOOOOOOOOOOOOOOO | OOOOOOOOOOOOOOOOOOOOOOOOOOOOOOOOOOOOOOOOOOOOOOOOOOOOOOOOOOOOOOOOOOOOOOOOOOOOOOOOOOOOOOOOOO | OOOOOOOOOOOOOOOOOOOOOOOOOOOOOOOOOOOOOOOOOOOOOOOOOOOOOOOOOOOOOOOOOOOOOOOOOOOOOOOOOOOOOOOOOO | OOOOOOOOOOOOOOOOOOOOOOOOOOOOOOOOOOOOOOOOOOOOOOOOOOOOOOOOOOOOOOOOOOOOOOOOOOOOOOOOOOOOOOOOOO | OOOOOOOOOOOOOOOOOOOOOOOOOOOOOOOOOOOOOOOOOOOOOOOOOOOOOOOOOOOOOOOOOOOOOOOOOOOOOOOOOOOOOOOOOO | OOOOOOOOOOOOOOOOOOOOOOOOOOOOOOOOOOOOOOOOOOOOOOOOOOOOOOOOOOOOOOOOOOOOOOOOOOOOOOOOOOOOOOOOOO | OOOOOOOOOOOOOOOOOOOOOOOOOOOOOOOOOOOOOOOOOOOOOOOOOOOOOOOOOOOOOOOOOOOOOOOOOOOOOOOOOOOOOOOOOO | OOOOOOOOOOOOOOOOOOOOOOOOOOOOOOOOOOOOOOOOOOOOOOOOOOOOOOOOOOOOOOOOOOOOOOOOOOOOOOOOOOOOOOOOOO |
| Second Source Change |  |  |  |  |  |  |  |  |  |
| Item | Location | Change Type | Foxconn P/N | Part Description | Manufacturer Full Name | Manufacturer P/N | RoHS | Sheet |  |
| OOOOOOOOOOOOOOOOOOOOOOOOOOOOOOOOOOOOOOOOOOOOOOOOOOOOOOOOOOOOOOOOOOOOOOOOOOOOOOOOOOOOOOOOOO | OOOOOOOOOOOOOOOOOOOOOOOOOOOOOOOOOOOOOOOOOOOOOOOOOOOOOOOOOOOOOOOOOOOOOOOOOOOOOOOOOOOOOOOOOO | OOOOOOOOOOOOOOOOOOOOOOOOOOOOOOOOOOOOOOOOOOOOOOOOOOOOOOOOOOOOOOOOOOOOOOOOOOOOOOOOOOOOOOOOOO | OOOOOOOOOOOOOOOOOOOOOOOOOOOOOOOOOOOOOOOOOOOOOOOOOOOOOOOOOOOOOOOOOOOOOOOOOOOOOOOOOOOOOOOOOO | OOOOOOOOOOOOOOOOOOOOOOOOOOOOOOOOOOOOOOOOOOOOOOOOOOOOOOOOOOOOOOOOOOOOOOOOOOOOOOOOOOOOOOOOOO | OOOOOOOOOOOOOOOOOOOOOOOOOOOOOOOOOOOOOOOOOOOOOOOOOOOOOOOOOOOOOOOOOOOOOOOOOOOOOOOOOOOOOOOOOO | OOOOOOOOOOOOOOOOOOOOOOOOOOOOOOOOOOOOOOOOOOOOOOOOOOOOOOOOOOOOOOOOOOOOOOOOOOOOOOOOOOOOOOOOOO | OOOOOOOOOOOOOOOOOOOOOOOOOOOOOOOOOOOOOOOOOOOOOOOOOOOOOOOOOOOOOOOOOOOOOOOOOOOOOOOOOOOOOOOOOO | OOOOOOOOOOOOOOOOOOOOOOOOOOOOOOOOOOOOOOOOOOOOOOOOOOOOOOOOOOOOOOOOOOOOOOOOOOOOOOOOOOOOOOOOOO | OOOOOOOOOOOOOOOOOOOOOOOOOOOOOOOOOOOOOOOOOOOOOOOOOOOOOOOOOOOOOOOOOOOOOOOOOOOOOOOOOOOOOOOOOO |
| Master Materials Change |  |  |  |  |  |  |  |  |  |
| Item | Foxconn P/N | Orig._Usage | New_Usage | Part Description | Manufacturer Full Name | Manufacturer P/N | RoHS | Location | Sheet |
| 1 | 41040HW00-191-G | 0 | 1 | EEPROM,AT24C02D-SSHM-T,1.7~3.6V,2K,I2C,G,SOIC-8,SMD | ATMEL CORPORATION | AT24C02D-SSHM-T | G | (+)U_BP_FRU1 | PWA BOM |
|  | 410401W00-214-G |  |  | EEPROM,M24C02-WMN6TP,2.5~5.5V,256*8,I2C,G,SOIC-8,SMD | ST MICRO ELECTRONICS,INC | M24C02-WMN6TP |  |  | PWA BOM |
|  | 41040J500-232-G |  |  | EEPROM,24AA024T-I/SN,1.7V~5.5V,2K,I2C,G,SOIC-8,SMD | MICROCHIP TECHNOLOGY INC | 24AA024T-I/SN |  |  | PWA BOM |
| 2 | 41040B600-191-G | 1 | 0 | EEPROM,AT24C02C-SSHM-T,1.7~5.5V,2K,I2C,G,SOIC-8,SMD | ATMEL CORPORATION | AT24C02C-SSHM-T | G | (-)U_BP_FRU1 | PWA BOM |
| OOOOOOOOOOOOOOOOOOOOOOOOOOOOOOOOOOOOOOOOOOOOOOOOOOOOOOOOOOOOOOOOOOOOOOOOOOOOOOOOOOOOOOOOOO | OOOOOOOOOOOOOOOOOOOOOOOOOOOOOOOOOOOOOOOOOOOOOOOOOOOOOOOOOOOOOOOOOOOOOOOOOOOOOOOOOOOOOOOOOO | OOOOOOOOOOOOOOOOOOOOOOOOOOOOOOOOOOOOOOOOOOOOOOOOOOOOOOOOOOOOOOOOOOOOOOOOOOOOOOOOOOOOOOOOOO | OOOOOOOOOOOOOOOOOOOOOOOOOOOOOOOOOOOOOOOOOOOOOOOOOOOOOOOOOOOOOOOOOOOOOOOOOOOOOOOOOOOOOOOOOO | OOOOOOOOOOOOOOOOOOOOOOOOOOOOOOOOOOOOOOOOOOOOOOOOOOOOOOOOOOOOOOOOOOOOOOOOOOOOOOOOOOOOOOOOOO | OOOOOOOOOOOOOOOOOOOOOOOOOOOOOOOOOOOOOOOOOOOOOOOOOOOOOOOOOOOOOOOOOOOOOOOOOOOOOOOOOOOOOOOOOO | OOOOOOOOOOOOOOOOOOOOOOOOOOOOOOOOOOOOOOOOOOOOOOOOOOOOOOOOOOOOOOOOOOOOOOOOOOOOOOOOOOOOOOOOOO | OOOOOOOOOOOOOOOOOOOOOOOOOOOOOOOOOOOOOOOOOOOOOOOOOOOOOOOOOOOOOOOOOOOOOOOOOOOOOOOOOOOOOOOOOO | OOOOOOOOOOOOOOOOOOOOOOOOOOOOOOOOOOOOOOOOOOOOOOOOOOOOOOOOOOOOOOOOOOOOOOOOOOOOOOOOOOOOOOOOOO | OOOOOOOOOOOOOOOOOOOOOOOOOOOOOOOOOOOOOOOOOOOOOOOOOOOOOOOOOOOOOOOOOOOOOOOOOOOOOOOOOOOOOOOOOO |
| TLA Parts Change |  |  |  |  |  |  |  |  |  |
| Item | Foxconn P/N | Qty | Part Description | Manufacturer Full Name | Manufacturer P/N | RoHS | Location | Remark | BOM |
| BOM Change List Date:Fri Sep 22 11:48:38 GMT+08:00 2017 |  |  |  |  |  |  |  |  |  |
| New BOM file : C:\<user>\Barreleye-G2_Tri-mode BPX24-DVT-X01-BOM-X06-20170922.xls |  |  |  |  |  |  |  |  |  |
| Old BOM file : C:\<user>\BPX24 0914.xls |  |  |  |  |  |  |  |  |  |
| ##### Add Parts |  |  |  |  |  |  |  |  |  |
| Item | Location | Qty | Foxconn P/N | Part Description | Manufacturer Full Name | Manufacturer P/N | RoHS | Sheet |  |
| 1 | C2272 | 1 | 620101T02-015-G | CAP,100nF,+/-10%,X7R,16V,G,SMD0402 | MURATA ELEC. NORTH AMERICA | GRM155R71C104K | G | PWA BOM |  |
|  |  |  | 620101T00-012-G | CAP,100nF,+/-10%,X7R,16V,G,SMD0402 | WALSIN TECHNOLOGY CORPORATION | 0402B104K160CT | G | PWA BOM |  |
|  |  |  | 620101T00-026-G | CAP,100nF,+/-10%,X7R,16V,G,SMD0402 | SAMSUNG SEMICONDUCTOR | CL05B104KO5NNNC | G | PWA BOM |  |
|  |  |  | 620101T00-015-G | CAP,100nF,+/-10%,X7R,16V,G,SMD0402 | MURATA ELEC. NORTH AMERICA | GRM155R71C104KA88D | G | PWA BOM |  |
| 2 | R2158 | 1 | 610107A00-017-G | RES,0 Ohm,+/-5%,1/16W,G,SMD0402 | KOA SPEER ELECTRONICS, INC. | RK73Z1ETTP | G | PWA BOM |  |
|  |  |  | 610107A00-012-G | RES,0 Ohm,+/-5%,1/16W,G,SMD0402 | WALSIN TECHNOLOGY CORPORATION | WR04X000PTL | G | PWA BOM |  |
|  |  |  | 610107A00-011-G | RES,0 Ohm,+/-5%,1/16W,G,SMD0402 | YAGEO CORPORATION COMPONENT | RC0402JR-070RL | G | PWA BOM |  |
|  |  |  | 610107A00-044-G | RES,0 Ohm,+/-5%,1/16W,G,SMD0402 | TA-I TECHNOLOGY CO., LTD | RM04JTN0 | G | PWA BOM |  |
|  |  |  | 610107A00-024-G | RES,0 Ohm,+/-5%,1/16W,G,SMD0402 | PANASONIC INDUSTRIAL CO.,LTD. | ERJ2GE0R00X | G | PWA BOM |  |
|  |  |  | 610107A00-029-G | RES,0 Ohm,+/-5%,1/16W,G,SMD0402 | VISHAY ENTER TECHNO LOGY.INC | CRCW04020000Z0ED | G | PWA BOM |  |
| 3 | U5 | 1 | 310101400-031-G | IC,Gate&Inverter,74LVC1G08GW,1.65~5.5V,G,SOT353-5,SMD | NXP SEMICONDUCTORS | 74LVC1G08GW | G | PWA BOM |  |
|  |  |  | 310103J00-223-G | IC,Gate&Inverter,NL17SZ08DFT2G,1.65~5.5V,G,SOT353-5,SMD | ON SEMICONDUCTOR CORP | NL17SZ08DFT2G | G | PWA BOM |  |
|  |  |  | 31010J400-131-G | IC,Gate&Inverter,TC7SZ08FU,1.8~5.5V,G,SSOP-5,SMD | TOSHIBA ELECTRONICS ASIA LTD | TC7SZ08FU | G | PWA BOM |  |
| ##### Remove Parts |  |  |  |  |  |  |  |  |  |
| Item | Location | Qty | Foxconn P/N | Part Description | Manufacturer Full Name | Manufacturer P/N | RoHS | Sheet |  |
| ##### Change Parts |  |  |  |  |  |  |  |  |  |
| Item | Location | Qty | Foxconn P/N | Part Description | Manufacturer Full Name | Manufacturer P/N | RoHS | Sheet | Remark |
| 1 | C2268,C2269 | 2 | 62012UW00-015-G | CAP,6.8pF,+/-0.05pF,NPO(C0G),25V,G,SMD0402 | MURATA ELEC. NORTH AMERICA | GRM1555C1E6R8WA01D | G | PWA BOM | In New BOM |
|  |  |  | 62012UW00-012-G | CAP,6.8pF,+/-0.05pF,NPO(C0G),25V,G,SMD0402 | WALSIN TECHNOLOGY CORPORATION | 0402N6R8A250CT |  | PWA BOM | In New BOM |
|  | C2268,C2269 | 2 | 62012UW00-015-G | CAP,6.8pF,+/-0.05pF,NPO(C0G),25V,G,SMD0402 | MURATA ELEC. NORTH AMERICA | GRM1555C1E6R8WA01D | G | PWA BOM | In Old BOM |
| 2 | R875,R877,R879,R881,R883,R885,R887,R889,R891,R893,R895,R897,R899,R901,R903,R905,R907,R909,R911,R913,R915,R917,R919,R921 | 24 | 61015K700-017-G | RES,3.3 Ohm,+/-5%,1/2W,G,SMD1210 | KOA SPEER ELECTRONICS, INC. | RK73B2ETTD3R3J | G | PWA BOM | In New BOM |
|  |  |  | 61015K700-011-G | RES,3.3 Ohm,+/-5%,1/2W,G,SMD1210 | YAGEO CORPORATION COMPONENT | RC1210JR-073R3L |  | PWA BOM | In New BOM |
|  | R875,R877,R879,R881,R883,R885,R887,R889,R891,R893,R895,R897,R899,R901,R903,R905,R907,R909,R911,R913,R915,R917,R919,R921 | 24 | 61015K700-017-G | RES,3.3 Ohm,+/-5%,1/2W,G,SMD1210 | KOA SPEER ELECTRONICS, INC. | RK73B2ETTD3R3J | G | PWA BOM | In Old BOM |
| 3 | R2060 | 1 | 610154800-017-G | RES,1 Ohm,+/-5%,1/8W,G,SMD0402 | KOA SPEER ELECTRONICS, INC. | SG73P1ETTP1R0J | G | PWA BOM | In New BOM |
|  |  |  | 610154800-011-G | RES,1 Ohm,+/-5%,1/8W,G,SMD0402 | YAGEO CORPORATION COMPONENT | RC0402JR-7W1RL |  | PWA BOM | In New BOM |
|  |  |  | 610154800-012-G | RES,1 Ohm,+/-5%,1/8W,G,SMD0402 | WALSIN TECHNOLOGY CORPORATION | WF04P1R0 JTL |  | PWA BOM | In New BOM |
|  | R2060 | 1 | 610154800-017-G | RES,1 Ohm,+/-5%,1/8W,G,SMD0402 | KOA SPEER ELECTRONICS, INC. | SG73P1ETTP1R0J | G | PWA BOM | In Old BOM |
| ##### Change Revision |  |  |  |  |  |  |  |  |  |
| Sheet | REV OF BOM | CUSTOMER | CUSTOMER P/N | PWA PN | PWA DESCRIPTION | PWA REV | DATE | Remark |  |
| OOOOOOOOOOOOOOOOOOOOOOOOOOOOOOOOOOOOOOOOOOOOOOOOOOOOOOOOOOOOOOOOOOOOOOOOOOOOOOOOOOOOOOOOOO | OOOOOOOOOOOOOOOOOOOOOOOOOOOOOOOOOOOOOOOOOOOOOOOOOOOOOOOOOOOOOOOOOOOOOOOOOOOOOOOOOOOOOOOOOO | OOOOOOOOOOOOOOOOOOOOOOOOOOOOOOOOOOOOOOOOOOOOOOOOOOOOOOOOOOOOOOOOOOOOOOOOOOOOOOOOOOOOOOOOOO | OOOOOOOOOOOOOOOOOOOOOOOOOOOOOOOOOOOOOOOOOOOOOOOOOOOOOOOOOOOOOOOOOOOOOOOOOOOOOOOOOOOOOOOOOO | OOOOOOOOOOOOOOOOOOOOOOOOOOOOOOOOOOOOOOOOOOOOOOOOOOOOOOOOOOOOOOOOOOOOOOOOOOOOOOOOOOOOOOOOOO | OOOOOOOOOOOOOOOOOOOOOOOOOOOOOOOOOOOOOOOOOOOOOOOOOOOOOOOOOOOOOOOOOOOOOOOOOOOOOOOOOOOOOOOOOO | OOOOOOOOOOOOOOOOOOOOOOOOOOOOOOOOOOOOOOOOOOOOOOOOOOOOOOOOOOOOOOOOOOOOOOOOOOOOOOOOOOOOOOOOOO | OOOOOOOOOOOOOOOOOOOOOOOOOOOOOOOOOOOOOOOOOOOOOOOOOOOOOOOOOOOOOOOOOOOOOOOOOOOOOOOOOOOOOOOOOO | OOOOOOOOOOOOOOOOOOOOOOOOOOOOOOOOOOOOOOOOOOOOOOOOOOOOOOOOOOOOOOOOOOOOOOOOOOOOOOOOOOOOOOOOOO | OOOOOOOOOOOOOOOOOOOOOOOOOOOOOOOOOOOOOOOOOOOOOOOOOOOOOOOOOOOOOOOOOOOOOOOOOOOOOOOOOOOOOOOOOO |
| Second Source Change |  |  |  |  |  |  |  |  |  |
| Item | Location | Change Type | Foxconn P/N | Part Description | Manufacturer Full Name | Manufacturer P/N | RoHS | Sheet |  |
| 1 | C2268,C2269 |  | 62012UW00-015-G | CAP,6.8pF,+/-0.05pF,NPO(C0G),25V,G,SMD0402 | MURATA ELEC. NORTH AMERICA | GRM1555C1E6R8WA01D | G | PWA BOM |  |
|  |  | ADD | 62012UW00-012-G | CAP,6.8pF,+/-0.05pF,NPO(C0G),25V,G,SMD0402 | WALSIN TECHNOLOGY CORPORATION | 0402N6R8A250CT |  | PWA BOM |  |
| 2 | R875,R877,R879,R881,R883,R885,R887,R889,R891,R893,R895,R897,R899,R901,R903,R905,R907,R909,R911,R913,R915,R917,R919,R921 |  | 61015K700-017-G | RES,3.3 Ohm,+/-5%,1/2W,G,SMD1210 | KOA SPEER ELECTRONICS, INC. | RK73B2ETTD3R3J | G | PWA BOM |  |
|  |  | ADD | 61015K700-011-G | RES,3.3 Ohm,+/-5%,1/2W,G,SMD1210 | YAGEO CORPORATION COMPONENT | RC1210JR-073R3L |  | PWA BOM |  |
| 3 | R2060 |  | 610154800-017-G | RES,1 Ohm,+/-5%,1/8W,G,SMD0402 | KOA SPEER ELECTRONICS, INC. | SG73P1ETTP1R0J | G | PWA BOM |  |
|  |  | ADD | 610154800-011-G | RES,1 Ohm,+/-5%,1/8W,G,SMD0402 | YAGEO CORPORATION COMPONENT | RC0402JR-7W1RL |  | PWA BOM |  |
|  |  | ADD | 610154800-012-G | RES,1 Ohm,+/-5%,1/8W,G,SMD0402 | WALSIN TECHNOLOGY CORPORATION | WF04P1R0 JTL |  | PWA BOM |  |
| OOOOOOOOOOOOOOOOOOOOOOOOOOOOOOOOOOOOOOOOOOOOOOOOOOOOOOOOOOOOOOOOOOOOOOOOOOOOOOOOOOOOOOOOOO | OOOOOOOOOOOOOOOOOOOOOOOOOOOOOOOOOOOOOOOOOOOOOOOOOOOOOOOOOOOOOOOOOOOOOOOOOOOOOOOOOOOOOOOOOO | OOOOOOOOOOOOOOOOOOOOOOOOOOOOOOOOOOOOOOOOOOOOOOOOOOOOOOOOOOOOOOOOOOOOOOOOOOOOOOOOOOOOOOOOOO | OOOOOOOOOOOOOOOOOOOOOOOOOOOOOOOOOOOOOOOOOOOOOOOOOOOOOOOOOOOOOOOOOOOOOOOOOOOOOOOOOOOOOOOOOO | OOOOOOOOOOOOOOOOOOOOOOOOOOOOOOOOOOOOOOOOOOOOOOOOOOOOOOOOOOOOOOOOOOOOOOOOOOOOOOOOOOOOOOOOOO | OOOOOOOOOOOOOOOOOOOOOOOOOOOOOOOOOOOOOOOOOOOOOOOOOOOOOOOOOOOOOOOOOOOOOOOOOOOOOOOOOOOOOOOOOO | OOOOOOOOOOOOOOOOOOOOOOOOOOOOOOOOOOOOOOOOOOOOOOOOOOOOOOOOOOOOOOOOOOOOOOOOOOOOOOOOOOOOOOOOOO | OOOOOOOOOOOOOOOOOOOOOOOOOOOOOOOOOOOOOOOOOOOOOOOOOOOOOOOOOOOOOOOOOOOOOOOOOOOOOOOOOOOOOOOOOO | OOOOOOOOOOOOOOOOOOOOOOOOOOOOOOOOOOOOOOOOOOOOOOOOOOOOOOOOOOOOOOOOOOOOOOOOOOOOOOOOOOOOOOOOOO | OOOOOOOOOOOOOOOOOOOOOOOOOOOOOOOOOOOOOOOOOOOOOOOOOOOOOOOOOOOOOOOOOOOOOOOOOOOOOOOOOOOOOOOOOO |
| Master Materials Change |  |  |  |  |  |  |  |  |  |
| Item | Foxconn P/N | Orig._Usage | New_Usage | Part Description | Manufacturer Full Name | Manufacturer P/N | RoHS | Location | Sheet |
| 1 | 620101T02-015-G | 144 | 145 | CAP,100nF,+/-10%,X7R,16V,G,SMD0402 | MURATA ELEC. NORTH AMERICA | GRM155R71C104K | G | (+)C2272 | PWA BOM |
|  | 620101T00-012-G |  |  | CAP,100nF,+/-10%,X7R,16V,G,SMD0402 | WALSIN TECHNOLOGY CORPORATION | 0402B104K160CT |  |  | PWA BOM |
|  | 620101T00-026-G |  |  | CAP,100nF,+/-10%,X7R,16V,G,SMD0402 | SAMSUNG SEMICONDUCTOR | CL05B104KO5NNNC |  |  | PWA BOM |
|  | 620101T00-015-G |  |  | CAP,100nF,+/-10%,X7R,16V,G,SMD0402 | MURATA ELEC. NORTH AMERICA | GRM155R71C104KA88D |  |  | PWA BOM |
| 2 | 610107A00-017-G | 125 | 126 | RES,0 Ohm,+/-5%,1/16W,G,SMD0402 | KOA SPEER ELECTRONICS, INC. | RK73Z1ETTP | G | (+)R2158 | PWA BOM |
|  | 610107A00-012-G |  |  | RES,0 Ohm,+/-5%,1/16W,G,SMD0402 | WALSIN TECHNOLOGY CORPORATION | WR04X000PTL |  |  | PWA BOM |
|  | 610107A00-011-G |  |  | RES,0 Ohm,+/-5%,1/16W,G,SMD0402 | YAGEO CORPORATION COMPONENT | RC0402JR-070RL |  |  | PWA BOM |
|  | 610107A00-044-G |  |  | RES,0 Ohm,+/-5%,1/16W,G,SMD0402 | TA-I TECHNOLOGY CO., LTD | RM04JTN0 |  |  | PWA BOM |
|  | 610107A00-024-G |  |  | RES,0 Ohm,+/-5%,1/16W,G,SMD0402 | PANASONIC INDUSTRIAL CO.,LTD. | ERJ2GE0R00X |  |  | PWA BOM |
|  | 610107A00-029-G |  |  | RES,0 Ohm,+/-5%,1/16W,G,SMD0402 | VISHAY ENTER TECHNO LOGY.INC | CRCW04020000Z0ED |  |  | PWA BOM |
| 3 | 310101400-031-G | 2 | 3 | IC,Gate&Inverter,74LVC1G08GW,1.65~5.5V,G,SOT353-5,SMD | NXP SEMICONDUCTORS | 74LVC1G08GW | G | (+)U5 | PWA BOM |
|  | 310103J00-223-G |  |  | IC,Gate&Inverter,NL17SZ08DFT2G,1.65~5.5V,G,SOT353-5,SMD | ON SEMICONDUCTOR CORP | NL17SZ08DFT2G |  |  | PWA BOM |
|  | 31010J400-131-G |  |  | IC,Gate&Inverter,TC7SZ08FU,1.8~5.5V,G,SSOP-5,SMD | TOSHIBA ELECTRONICS ASIA LTD | TC7SZ08FU |  |  | PWA BOM |
| OOOOOOOOOOOOOOOOOOOOOOOOOOOOOOOOOOOOOOOOOOOOOOOOOOOOOOOOOOOOOOOOOOOOOOOOOOOOOOOOOOOOOOOOOO | OOOOOOOOOOOOOOOOOOOOOOOOOOOOOOOOOOOOOOOOOOOOOOOOOOOOOOOOOOOOOOOOOOOOOOOOOOOOOOOOOOOOOOOOOO | OOOOOOOOOOOOOOOOOOOOOOOOOOOOOOOOOOOOOOOOOOOOOOOOOOOOOOOOOOOOOOOOOOOOOOOOOOOOOOOOOOOOOOOOOO | OOOOOOOOOOOOOOOOOOOOOOOOOOOOOOOOOOOOOOOOOOOOOOOOOOOOOOOOOOOOOOOOOOOOOOOOOOOOOOOOOOOOOOOOOO | OOOOOOOOOOOOOOOOOOOOOOOOOOOOOOOOOOOOOOOOOOOOOOOOOOOOOOOOOOOOOOOOOOOOOOOOOOOOOOOOOOOOOOOOOO | OOOOOOOOOOOOOOOOOOOOOOOOOOOOOOOOOOOOOOOOOOOOOOOOOOOOOOOOOOOOOOOOOOOOOOOOOOOOOOOOOOOOOOOOOO | OOOOOOOOOOOOOOOOOOOOOOOOOOOOOOOOOOOOOOOOOOOOOOOOOOOOOOOOOOOOOOOOOOOOOOOOOOOOOOOOOOOOOOOOOO | OOOOOOOOOOOOOOOOOOOOOOOOOOOOOOOOOOOOOOOOOOOOOOOOOOOOOOOOOOOOOOOOOOOOOOOOOOOOOOOOOOOOOOOOOO | OOOOOOOOOOOOOOOOOOOOOOOOOOOOOOOOOOOOOOOOOOOOOOOOOOOOOOOOOOOOOOOOOOOOOOOOOOOOOOOOOOOOOOOOOO |  |
| TLA Parts Change |  |  |  |  |  |  |  |  |  |
| Item | Foxconn P/N | Qty | Part Description | Manufacturer Full Name | Manufacturer P/N | RoHS | Location | Remark |  |
| BOM Change List Date:Fri Sep 29 11:25:41 GMT+08:00 2017 |  |  |  |  |  |  |  |  |  |
| New BOM file : E:\barreleye g2\0928\Barreleye-G2_Tri-mode BPX24-DVT-X01-BOM-X07-20170928.xls |  |  |  |  |  |  |  |  |  |
| Old BOM file : E:\barreleye g2\0928\BPX240922.xls |  |  |  |  |  |  |  |  |  |
| ##### Add Parts |  |  |  |  |  |  |  |  |  |
| Item | Location | Qty | Foxconn P/N | Part Description | Manufacturer Full Name | Manufacturer P/N | RoHS | Sheet |  |
| 1 | R2180,R2181,R2182,R2183,R2184,R2185,R2186,R2187,R2188,R2189,R2190,R2191,R2192,R2193,R2194,R2195,R2196,R2197,R2198,R2199 | 20 | 610107A00-017-G | RES,0 Ohm,+/-5%,1/16W,G,SMD0402 | KOA SPEER ELECTRONICS, INC. | RK73Z1ETTP | G | PWA BOM |  |
|  |  |  | 610107A00-012-G | RES,0 Ohm,+/-5%,1/16W,G,SMD0402 | WALSIN TECHNOLOGY CORPORATION | WR04X000PTL | G | PWA BOM |  |
|  |  |  | 610107A00-011-G | RES,0 Ohm,+/-5%,1/16W,G,SMD0402 | YAGEO CORPORATION COMPONENT | RC0402JR-070RL | G | PWA BOM |  |
|  |  |  | 610107A00-044-G | RES,0 Ohm,+/-5%,1/16W,G,SMD0402 | TA-I TECHNOLOGY CO., LTD | RM04JTN0 | G | PWA BOM |  |
|  |  |  | 610107A00-024-G | RES,0 Ohm,+/-5%,1/16W,G,SMD0402 | PANASONIC INDUSTRIAL CO.,LTD. | ERJ2GE0R00X | G | PWA BOM |  |
|  |  |  | 610107A00-029-G | RES,0 Ohm,+/-5%,1/16W,G,SMD0402 | VISHAY ENTER TECHNO LOGY.INC | CRCW04020000Z0ED | G | PWA BOM |  |
| 2 | R2160,R2161,R2162,R2163,R2164,R2165,R2166,R2167,R2168,R2169,R2170,R2171,R2172,R2173,R2174,R2175,R2176,R2177,R2178,R2179 | 20 | 610107B00-017-G | RES,4.7KOhm,+/-5%,1/16W,G,SMD0402 | KOA SPEER ELECTRONICS, INC. | RK73B1ETTP472J | G | PWA BOM |  |
|  |  |  | 610107B00-012-G | RES,4.7KOhm,+/-5%,1/16W,G,SMD0402 | WALSIN TECHNOLOGY CORPORATION | WR04X472JTL | G | PWA BOM |  |
|  |  |  | 610107B00-011-G | RES,4.7KOhm,+/-5%,1/16W,G,SMD0402 | YAGEO CORPORATION COMPONENT | RC0402JR-074K7L | G | PWA BOM |  |
|  |  |  | 610107B00-044-G | RES,4.7KOhm,+/-5%,1/16W,G,SMD0402 | TA-I TECHNOLOGY CO., LTD | RM04JTN472 | G | PWA BOM |  |
|  |  |  | 610107B00-024-G | RES,4.7KOhm,+/-5%,1/16W,G,SMD0402 | PANASONIC INDUSTRIAL CO.,LTD. | ERJ2GEJ472X | G | PWA BOM |  |
|  |  |  | 610107B00-029-G | RES,4.7KOhm,+/-5%,1/16W,G,SMD0402 | VISHAY ENTER TECHNO LOGY.INC | CRCW04024K70JNED | G | PWA BOM |  |
| ##### Remove Parts |  |  |  |  |  |  |  |  |  |
| Item | Location | Qty | Foxconn P/N | Part Description | Manufacturer Full Name | Manufacturer P/N | RoHS | Sheet |  |
| ##### Change Parts |  |  |  |  |  |  |  |  |  |
| Item | Location | Qty | Foxconn P/N | Part Description | Manufacturer Full Name | Manufacturer P/N | RoHS | Sheet | Remark |
| 5 | JSAS1,JPCIE1,JSAS2,JPCIE2,JSAS3,JPCIE3,JPCIE4,JPCIE5,JPCIE6,JPCIE7 | 10 | 340718A00-245-G | CONN,SAS,V/T,0.6mm,30u,G,SMD-74 | AMPHENOL SHANGHAI CORP. | U10-B074-250T | G | PWA BOM | In New BOM |
|  | JSAS1,JPCIE1,JSAS2,JPCIE2,JSAS3,JPCIE3,JPCIE4,JPCIE5,JPCIE6,JPCIE7 | 10 | 340718900-245-G | CONN,SAS,V/T,0.6mm,30u,G,SMD-74 | AMPHENOL SHANGHAI CORP. | U10-B074-260T | G | PWA BOM | In Old BOM |
| ##### Change Revision |  |  |  |  |  |  |  |  |  |
| Sheet | REV OF BOM | CUSTOMER | CUSTOMER P/N | PWA PN | PWA DESCRIPTION | PWA REV | DATE | Remark |  |
| OOOOOOOOOOOOOOOOOOOOOOOOOOOOOOOOOOOOOOOOOOOOOOOOOOOOOOOOOOOOOOOOOOOOOOOOOOOOOOOOOOOOOOOOOO | OOOOOOOOOOOOOOOOOOOOOOOOOOOOOOOOOOOOOOOOOOOOOOOOOOOOOOOOOOOOOOOOOOOOOOOOOOOOOOOOOOOOOOOOOO | OOOOOOOOOOOOOOOOOOOOOOOOOOOOOOOOOOOOOOOOOOOOOOOOOOOOOOOOOOOOOOOOOOOOOOOOOOOOOOOOOOOOOOOOOO | OOOOOOOOOOOOOOOOOOOOOOOOOOOOOOOOOOOOOOOOOOOOOOOOOOOOOOOOOOOOOOOOOOOOOOOOOOOOOOOOOOOOOOOOOO | OOOOOOOOOOOOOOOOOOOOOOOOOOOOOOOOOOOOOOOOOOOOOOOOOOOOOOOOOOOOOOOOOOOOOOOOOOOOOOOOOOOOOOOOOO | OOOOOOOOOOOOOOOOOOOOOOOOOOOOOOOOOOOOOOOOOOOOOOOOOOOOOOOOOOOOOOOOOOOOOOOOOOOOOOOOOOOOOOOOOO | OOOOOOOOOOOOOOOOOOOOOOOOOOOOOOOOOOOOOOOOOOOOOOOOOOOOOOOOOOOOOOOOOOOOOOOOOOOOOOOOOOOOOOOOOO | OOOOOOOOOOOOOOOOOOOOOOOOOOOOOOOOOOOOOOOOOOOOOOOOOOOOOOOOOOOOOOOOOOOOOOOOOOOOOOOOOOOOOOOOOO | OOOOOOOOOOOOOOOOOOOOOOOOOOOOOOOOOOOOOOOOOOOOOOOOOOOOOOOOOOOOOOOOOOOOOOOOOOOOOOOOOOOOOOOOOO | OOOOOOOOOOOOOOOOOOOOOOOOOOOOOOOOOOOOOOOOOOOOOOOOOOOOOOOOOOOOOOOOOOOOOOOOOOOOOOOOOOOOOOOOOO |
| Second Source Change |  |  |  |  |  |  |  |  |  |
| Item | Location | Change Type | Foxconn P/N | Part Description | Manufacturer Full Name | Manufacturer P/N | RoHS | Sheet |  |
| OOOOOOOOOOOOOOOOOOOOOOOOOOOOOOOOOOOOOOOOOOOOOOOOOOOOOOOOOOOOOOOOOOOOOOOOOOOOOOOOOOOOOOOOOO | OOOOOOOOOOOOOOOOOOOOOOOOOOOOOOOOOOOOOOOOOOOOOOOOOOOOOOOOOOOOOOOOOOOOOOOOOOOOOOOOOOOOOOOOOO | OOOOOOOOOOOOOOOOOOOOOOOOOOOOOOOOOOOOOOOOOOOOOOOOOOOOOOOOOOOOOOOOOOOOOOOOOOOOOOOOOOOOOOOOOO | OOOOOOOOOOOOOOOOOOOOOOOOOOOOOOOOOOOOOOOOOOOOOOOOOOOOOOOOOOOOOOOOOOOOOOOOOOOOOOOOOOOOOOOOOO | OOOOOOOOOOOOOOOOOOOOOOOOOOOOOOOOOOOOOOOOOOOOOOOOOOOOOOOOOOOOOOOOOOOOOOOOOOOOOOOOOOOOOOOOOO | OOOOOOOOOOOOOOOOOOOOOOOOOOOOOOOOOOOOOOOOOOOOOOOOOOOOOOOOOOOOOOOOOOOOOOOOOOOOOOOOOOOOOOOOOO | OOOOOOOOOOOOOOOOOOOOOOOOOOOOOOOOOOOOOOOOOOOOOOOOOOOOOOOOOOOOOOOOOOOOOOOOOOOOOOOOOOOOOOOOOO | OOOOOOOOOOOOOOOOOOOOOOOOOOOOOOOOOOOOOOOOOOOOOOOOOOOOOOOOOOOOOOOOOOOOOOOOOOOOOOOOOOOOOOOOOO | OOOOOOOOOOOOOOOOOOOOOOOOOOOOOOOOOOOOOOOOOOOOOOOOOOOOOOOOOOOOOOOOOOOOOOOOOOOOOOOOOOOOOOOOOO | OOOOOOOOOOOOOOOOOOOOOOOOOOOOOOOOOOOOOOOOOOOOOOOOOOOOOOOOOOOOOOOOOOOOOOOOOOOOOOOOOOOOOOOOOO |
| Master Materials Change |  |  |  |  |  |  |  |  |  |
| Item | Foxconn P/N | Orig._Usage | New_Usage | Part Description | Manufacturer Full Name | Manufacturer P/N | RoHS | Location | Sheet |
| 1 | 610107A00-017-G | 126 | 146 | RES,0 Ohm,+/-5%,1/16W,G,SMD0402 | KOA SPEER ELECTRONICS, INC. | RK73Z1ETTP | G | (+)R2180,R2181,R2182,R2183,R2184,R2185,R2186,R2187,R2188,R2189,R2190,R2191,R2192,R2193,R2194,R2195,R2196,R2197,R2198,R2199 | PWA BOM |
|  | 610107A00-012-G |  |  | RES,0 Ohm,+/-5%,1/16W,G,SMD0402 | WALSIN TECHNOLOGY CORPORATION | WR04X000PTL |  |  | PWA BOM |
|  | 610107A00-011-G |  |  | RES,0 Ohm,+/-5%,1/16W,G,SMD0402 | YAGEO CORPORATION COMPONENT | RC0402JR-070RL |  |  | PWA BOM |
|  | 610107A00-044-G |  |  | RES,0 Ohm,+/-5%,1/16W,G,SMD0402 | TA-I TECHNOLOGY CO., LTD | RM04JTN0 |  |  | PWA BOM |
|  | 610107A00-024-G |  |  | RES,0 Ohm,+/-5%,1/16W,G,SMD0402 | PANASONIC INDUSTRIAL CO.,LTD. | ERJ2GE0R00X |  |  | PWA BOM |
|  | 610107A00-029-G |  |  | RES,0 Ohm,+/-5%,1/16W,G,SMD0402 | VISHAY ENTER TECHNO LOGY.INC | CRCW04020000Z0ED |  |  | PWA BOM |
| 2 | 610107B00-017-G | 174 | 194 | RES,4.7KOhm,+/-5%,1/16W,G,SMD0402 | KOA SPEER ELECTRONICS, INC. | RK73B1ETTP472J | G | (+)R2160,R2161,R2162,R2163,R2164,R2165,R2166,R2167,R2168,R2169,R2170,R2171,R2172,R2173,R2174,R2175,R2176,R2177,R2178,R2179 | PWA BOM |
|  | 610107B00-012-G |  |  | RES,4.7KOhm,+/-5%,1/16W,G,SMD0402 | WALSIN TECHNOLOGY CORPORATION | WR04X472JTL |  |  | PWA BOM |
|  | 610107B00-011-G |  |  | RES,4.7KOhm,+/-5%,1/16W,G,SMD0402 | YAGEO CORPORATION COMPONENT | RC0402JR-074K7L |  |  | PWA BOM |
|  | 610107B00-044-G |  |  | RES,4.7KOhm,+/-5%,1/16W,G,SMD0402 | TA-I TECHNOLOGY CO., LTD | RM04JTN472 |  |  | PWA BOM |
|  | 610107B00-024-G |  |  | RES,4.7KOhm,+/-5%,1/16W,G,SMD0402 | PANASONIC INDUSTRIAL CO.,LTD. | ERJ2GEJ472X |  |  | PWA BOM |
|  | 610107B00-029-G |  |  | RES,4.7KOhm,+/-5%,1/16W,G,SMD0402 | VISHAY ENTER TECHNO LOGY.INC | CRCW04024K70JNED |  |  | PWA BOM |
| 3 | 340718A00-245-G | 0 | 10 | CONN,SAS,V/T,0.6mm,30u,G,SMD-74 | AMPHENOL SHANGHAI CORP. | U10-B074-250T | G | (+)JSAS1,JPCIE1,JSAS2,JPCIE2,JSAS3,JPCIE3,JPCIE4,JPCIE5,JPCIE6,JPCIE7 | PWA BOM |
| 4 | 340718900-245-G | 10 | 0 | CONN,SAS,V/T,0.6mm,30u,G,SMD-74 | AMPHENOL SHANGHAI CORP. | U10-B074-260T | G | (-)JSAS1,JPCIE1,JSAS2,JPCIE2,JSAS3,JPCIE3,JPCIE4,JPCIE5,JPCIE6,JPCIE7 | PWA BOM |
| OOOOOOOOOOOOOOOOOOOOOOOOOOOOOOOOOOOOOOOOOOOOOOOOOOOOOOOOOOOOOOOOOOOOOOOOOOOOOOOOOOOOOOOOOO | OOOOOOOOOOOOOOOOOOOOOOOOOOOOOOOOOOOOOOOOOOOOOOOOOOOOOOOOOOOOOOOOOOOOOOOOOOOOOOOOOOOOOOOOOO | OOOOOOOOOOOOOOOOOOOOOOOOOOOOOOOOOOOOOOOOOOOOOOOOOOOOOOOOOOOOOOOOOOOOOOOOOOOOOOOOOOOOOOOOOO | OOOOOOOOOOOOOOOOOOOOOOOOOOOOOOOOOOOOOOOOOOOOOOOOOOOOOOOOOOOOOOOOOOOOOOOOOOOOOOOOOOOOOOOOOO | OOOOOOOOOOOOOOOOOOOOOOOOOOOOOOOOOOOOOOOOOOOOOOOOOOOOOOOOOOOOOOOOOOOOOOOOOOOOOOOOOOOOOOOOOO | OOOOOOOOOOOOOOOOOOOOOOOOOOOOOOOOOOOOOOOOOOOOOOOOOOOOOOOOOOOOOOOOOOOOOOOOOOOOOOOOOOOOOOOOOO | OOOOOOOOOOOOOOOOOOOOOOOOOOOOOOOOOOOOOOOOOOOOOOOOOOOOOOOOOOOOOOOOOOOOOOOOOOOOOOOOOOOOOOOOOO | OOOOOOOOOOOOOOOOOOOOOOOOOOOOOOOOOOOOOOOOOOOOOOOOOOOOOOOOOOOOOOOOOOOOOOOOOOOOOOOOOOOOOOOOOO | OOOOOOOOOOOOOOOOOOOOOOOOOOOOOOOOOOOOOOOOOOOOOOOOOOOOOOOOOOOOOOOOOOOOOOOOOOOOOOOOOOOOOOOOOO |  |
| TLA Parts Change |  |  |  |  |  |  |  |  |  |
| Item | Foxconn P/N | Qty | Part Description | Manufacturer Full Name | Manufacturer P/N | RoHS | Location | Remark |  |
| BOM Change List Date:Tue Oct 17 10:14:54 GMT+08:00 2017 |  |  |  |  |  |  |  |  |  |
| New BOM file : E:\barreleye g2\1016\BPX24 1017.xls |  |  |  |  |  |  |  |  |  |
| Old BOM file : E:\barreleye g2\1016\BPX24 0929.xls |  |  |  |  |  |  |  |  |  |
| ##### Add Parts |  |  |  |  |  |  |  |  |  |
| Item | Location | Qty | Foxconn P/N | Part Description | Manufacturer Full Name | Manufacturer P/N | RoHS | Sheet |  |
| ##### Remove Parts |  |  |  |  |  |  |  |  |  |
| Item | Location | Qty | Foxconn P/N | Part Description | Manufacturer Full Name | Manufacturer P/N | RoHS | Sheet |  |
| 1 | R50,R51,R52,R53,R96,R97,R1569,R1570,R1571,R1572,R1573,R1574,R1575,R1576,R1577,R1578,R1579,R1580,R1581,R1582,R1583,R1584,R1585,R1586,R1587,R1588,R1589,R1590,R1591,R1592,R1593,R1594,R1595,R1596,R1597,R1598,R1599,R1600,R1601,R1602 | 40 | 610107B00-017-G | RES,4.7KOhm,+/-5%,1/16W,G,SMD0402 | KOA SPEER ELECTRONICS, INC. | RK73B1ETTP472J | G | PWA BOM |  |
|  |  |  | 610107B00-012-G | RES,4.7KOhm,+/-5%,1/16W,G,SMD0402 | WALSIN TECHNOLOGY CORPORATION | WR04X472JTL | G | PWA BOM |  |
|  |  |  | 610107B00-011-G | RES,4.7KOhm,+/-5%,1/16W,G,SMD0402 | YAGEO CORPORATION COMPONENT | RC0402JR-074K7L | G | PWA BOM |  |
|  |  |  | 610107B00-044-G | RES,4.7KOhm,+/-5%,1/16W,G,SMD0402 | TA-I TECHNOLOGY CO., LTD | RM04JTN472 | G | PWA BOM |  |
|  |  |  | 610107B00-024-G | RES,4.7KOhm,+/-5%,1/16W,G,SMD0402 | PANASONIC INDUSTRIAL CO.,LTD. | ERJ2GEJ472X | G | PWA BOM |  |
|  |  |  | 610107B00-029-G | RES,4.7KOhm,+/-5%,1/16W,G,SMD0402 | VISHAY ENTER TECHNO LOGY.INC | CRCW04024K70JNED | G | PWA BOM |  |
| ##### Change Parts |  |  |  |  |  |  |  |  |  |
| Item | Location | Qty | Foxconn P/N | Part Description | Manufacturer Full Name | Manufacturer P/N | RoHS | Sheet | Remark |
| 1 | PCB | 1 | 0101FGA00-000-G | PCB,Zaius-Tri-mode BPX24 DVT-X01,OSP,Blu,22L,21.122*3.470,G | NON DEDICATED | 0101FGA00-000-G | G | PWA BOM | In New BOM |
|  | PCB | 1 | PCB | PCB | PCB | PCB | G | PWA BOM | In Old BOM |
| ##### Change Revision |  |  |  |  |  |  |  |  |  |
| Sheet | REV OF BOM | CUSTOMER | CUSTOMER P/N | PWA PN | PWA DESCRIPTION | PWA REV | DATE | Remark |  |
| OOOOOOOOOOOOOOOOOOOOOOOOOOOOOOOOOOOOOOOOOOOOOOOOOOOOOOOOOOOOOOOOOOOOOOOOOOOOOOOOOOOOOOOOOO | OOOOOOOOOOOOOOOOOOOOOOOOOOOOOOOOOOOOOOOOOOOOOOOOOOOOOOOOOOOOOOOOOOOOOOOOOOOOOOOOOOOOOOOOOO | OOOOOOOOOOOOOOOOOOOOOOOOOOOOOOOOOOOOOOOOOOOOOOOOOOOOOOOOOOOOOOOOOOOOOOOOOOOOOOOOOOOOOOOOOO | OOOOOOOOOOOOOOOOOOOOOOOOOOOOOOOOOOOOOOOOOOOOOOOOOOOOOOOOOOOOOOOOOOOOOOOOOOOOOOOOOOOOOOOOOO | OOOOOOOOOOOOOOOOOOOOOOOOOOOOOOOOOOOOOOOOOOOOOOOOOOOOOOOOOOOOOOOOOOOOOOOOOOOOOOOOOOOOOOOOOO | OOOOOOOOOOOOOOOOOOOOOOOOOOOOOOOOOOOOOOOOOOOOOOOOOOOOOOOOOOOOOOOOOOOOOOOOOOOOOOOOOOOOOOOOOO | OOOOOOOOOOOOOOOOOOOOOOOOOOOOOOOOOOOOOOOOOOOOOOOOOOOOOOOOOOOOOOOOOOOOOOOOOOOOOOOOOOOOOOOOOO | OOOOOOOOOOOOOOOOOOOOOOOOOOOOOOOOOOOOOOOOOOOOOOOOOOOOOOOOOOOOOOOOOOOOOOOOOOOOOOOOOOOOOOOOOO | OOOOOOOOOOOOOOOOOOOOOOOOOOOOOOOOOOOOOOOOOOOOOOOOOOOOOOOOOOOOOOOOOOOOOOOOOOOOOOOOOOOOOOOOOO | OOOOOOOOOOOOOOOOOOOOOOOOOOOOOOOOOOOOOOOOOOOOOOOOOOOOOOOOOOOOOOOOOOOOOOOOOOOOOOOOOOOOOOOOOO |
| Second Source Change |  |  |  |  |  |  |  |  |  |
| Item | Location | Change Type | Foxconn P/N | Part Description | Manufacturer Full Name | Manufacturer P/N | RoHS | Sheet |  |
| OOOOOOOOOOOOOOOOOOOOOOOOOOOOOOOOOOOOOOOOOOOOOOOOOOOOOOOOOOOOOOOOOOOOOOOOOOOOOOOOOOOOOOOOOO | OOOOOOOOOOOOOOOOOOOOOOOOOOOOOOOOOOOOOOOOOOOOOOOOOOOOOOOOOOOOOOOOOOOOOOOOOOOOOOOOOOOOOOOOOO | OOOOOOOOOOOOOOOOOOOOOOOOOOOOOOOOOOOOOOOOOOOOOOOOOOOOOOOOOOOOOOOOOOOOOOOOOOOOOOOOOOOOOOOOOO | OOOOOOOOOOOOOOOOOOOOOOOOOOOOOOOOOOOOOOOOOOOOOOOOOOOOOOOOOOOOOOOOOOOOOOOOOOOOOOOOOOOOOOOOOO | OOOOOOOOOOOOOOOOOOOOOOOOOOOOOOOOOOOOOOOOOOOOOOOOOOOOOOOOOOOOOOOOOOOOOOOOOOOOOOOOOOOOOOOOOO | OOOOOOOOOOOOOOOOOOOOOOOOOOOOOOOOOOOOOOOOOOOOOOOOOOOOOOOOOOOOOOOOOOOOOOOOOOOOOOOOOOOOOOOOOO | OOOOOOOOOOOOOOOOOOOOOOOOOOOOOOOOOOOOOOOOOOOOOOOOOOOOOOOOOOOOOOOOOOOOOOOOOOOOOOOOOOOOOOOOOO | OOOOOOOOOOOOOOOOOOOOOOOOOOOOOOOOOOOOOOOOOOOOOOOOOOOOOOOOOOOOOOOOOOOOOOOOOOOOOOOOOOOOOOOOOO | OOOOOOOOOOOOOOOOOOOOOOOOOOOOOOOOOOOOOOOOOOOOOOOOOOOOOOOOOOOOOOOOOOOOOOOOOOOOOOOOOOOOOOOOOO | OOOOOOOOOOOOOOOOOOOOOOOOOOOOOOOOOOOOOOOOOOOOOOOOOOOOOOOOOOOOOOOOOOOOOOOOOOOOOOOOOOOOOOOOOO |
| Master Materials Change |  |  |  |  |  |  |  |  |  |
| Item | Foxconn P/N | Orig._Usage | New_Usage | Part Description | Manufacturer Full Name | Manufacturer P/N | RoHS | Location | Sheet |
| 1 | 0101FGA00-000-G | 0 | 1 | PCB,Zaius-Tri-mode BPX24 DVT-X01,OSP,Blu,22L,21.122*3.470,G | NON DEDICATED | 0101FGA00-000-G | G | (+)PCB | PWA BOM |
| 2 | 610107B00-017-G | 194 | 154 | RES,4.7KOhm,+/-5%,1/16W,G,SMD0402 | KOA SPEER ELECTRONICS, INC. | RK73B1ETTP472J | G | (-)R50,R51,R52,R53,R96,R97,R1569,R1570,R1571,R1572,R1573,R1574,R1575,R1576,R1577,R1578,R1579,R1580,R1581,R1582,R1583,R1584,R1585,R1586,R1587,R1588,R1589,R1590,R1591,R1592,R1593,R1594,R1595,R1596,R1597,R1598,R1599,R1600,R1601,R1602 | PWA BOM |
|  | 610107B00-012-G |  |  | RES,4.7KOhm,+/-5%,1/16W,G,SMD0402 | WALSIN TECHNOLOGY CORPORATION | WR04X472JTL |  |  | PWA BOM |
|  | 610107B00-011-G |  |  | RES,4.7KOhm,+/-5%,1/16W,G,SMD0402 | YAGEO CORPORATION COMPONENT | RC0402JR-074K7L |  |  | PWA BOM |
|  | 610107B00-044-G |  |  | RES,4.7KOhm,+/-5%,1/16W,G,SMD0402 | TA-I TECHNOLOGY CO., LTD | RM04JTN472 |  |  | PWA BOM |
|  | 610107B00-024-G |  |  | RES,4.7KOhm,+/-5%,1/16W,G,SMD0402 | PANASONIC INDUSTRIAL CO.,LTD. | ERJ2GEJ472X |  |  | PWA BOM |
|  | 610107B00-029-G |  |  | RES,4.7KOhm,+/-5%,1/16W,G,SMD0402 | VISHAY ENTER TECHNO LOGY.INC | CRCW04024K70JNED |  |  | PWA BOM |
| 3 | PCB | 1 | 0 | PCB | PCB | PCB | G | (-)PCB | PWA BOM |
| OOOOOOOOOOOOOOOOOOOOOOOOOOOOOOOOOOOOOOOOOOOOOOOOOOOOOOOOOOOOOOOOOOOOOOOOOOOOOOOOOOOOOOOOOO | OOOOOOOOOOOOOOOOOOOOOOOOOOOOOOOOOOOOOOOOOOOOOOOOOOOOOOOOOOOOOOOOOOOOOOOOOOOOOOOOOOOOOOOOOO | OOOOOOOOOOOOOOOOOOOOOOOOOOOOOOOOOOOOOOOOOOOOOOOOOOOOOOOOOOOOOOOOOOOOOOOOOOOOOOOOOOOOOOOOOO | OOOOOOOOOOOOOOOOOOOOOOOOOOOOOOOOOOOOOOOOOOOOOOOOOOOOOOOOOOOOOOOOOOOOOOOOOOOOOOOOOOOOOOOOOO | OOOOOOOOOOOOOOOOOOOOOOOOOOOOOOOOOOOOOOOOOOOOOOOOOOOOOOOOOOOOOOOOOOOOOOOOOOOOOOOOOOOOOOOOOO | OOOOOOOOOOOOOOOOOOOOOOOOOOOOOOOOOOOOOOOOOOOOOOOOOOOOOOOOOOOOOOOOOOOOOOOOOOOOOOOOOOOOOOOOOO | OOOOOOOOOOOOOOOOOOOOOOOOOOOOOOOOOOOOOOOOOOOOOOOOOOOOOOOOOOOOOOOOOOOOOOOOOOOOOOOOOOOOOOOOOO | OOOOOOOOOOOOOOOOOOOOOOOOOOOOOOOOOOOOOOOOOOOOOOOOOOOOOOOOOOOOOOOOOOOOOOOOOOOOOOOOOOOOOOOOOO | OOOOOOOOOOOOOOOOOOOOOOOOOOOOOOOOOOOOOOOOOOOOOOOOOOOOOOOOOOOOOOOOOOOOOOOOOOOOOOOOOOOOOOOOOO |  |
| TLA Parts Change |  |  |  |  |  |  |  |  |  |
| Item | Foxconn P/N | Qty | Part Description | Manufacturer Full Name | Manufacturer P/N | RoHS | Location | Remark |  |
| BOM Change List Date:Tue Oct 24 15:28:12 CST 2017 |  |  |  |  |  |  |  |  |  |
| New BOM file : E:\barreleye g2\1024\BPX24 1024.xls |  |  |  |  |  |  |  |  |  |
| Old BOM file : E:\barreleye g2\1024\BPX24 1017.xls |  |  |  |  |  |  |  |  |  |
| ##### Add Parts |  |  |  |  |  |  |  |  |  |
| Item | Location | Qty | Foxconn P/N | Part Description | Manufacturer Full Name | Manufacturer P/N | RoHS | Sheet |  |
| ##### Remove Parts |  |  |  |  |  |  |  |  |  |
| Item | Location | Qty | Foxconn P/N | Part Description | Manufacturer Full Name | Manufacturer P/N | RoHS | Sheet |  |
| 1 | R2160,R2161,R2162,R2163,R2164,R2165,R2166,R2167,R2168,R2169,R2170,R2171,R2172,R2173,R2174,R2175,R2176,R2177,R2178,R2179 | 20 | 610107B00-017-G | RES,4.7KOhm,+/-5%,1/16W,G,SMD0402 | KOA SPEER ELECTRONICS, INC. | RK73B1ETTP472J | G | PWA BOM |  |
|  |  |  | 610107B00-012-G | RES,4.7KOhm,+/-5%,1/16W,G,SMD0402 | WALSIN TECHNOLOGY CORPORATION | WR04X472JTL | G | PWA BOM |  |
|  |  |  | 610107B00-011-G | RES,4.7KOhm,+/-5%,1/16W,G,SMD0402 | YAGEO CORPORATION COMPONENT | RC0402JR-074K7L | G | PWA BOM |  |
|  |  |  | 610107B00-044-G | RES,4.7KOhm,+/-5%,1/16W,G,SMD0402 | TA-I TECHNOLOGY CO., LTD | RM04JTN472 | G | PWA BOM |  |
|  |  |  | 610107B00-024-G | RES,4.7KOhm,+/-5%,1/16W,G,SMD0402 | PANASONIC INDUSTRIAL CO.,LTD. | ERJ2GEJ472X | G | PWA BOM |  |
|  |  |  | 610107B00-029-G | RES,4.7KOhm,+/-5%,1/16W,G,SMD0402 | VISHAY ENTER TECHNO LOGY.INC | CRCW04024K70JNED | G | PWA BOM |  |
| ##### Change Parts |  |  |  |  |  |  |  |  |  |
| Item | Location | Qty | Foxconn P/N | Part Description | Manufacturer Full Name | Manufacturer P/N | RoHS | Sheet | Remark |
| 1 | PCB | 1 | 0101FGA00-000-G | PCB,Zaius-Tri-mode BPX24 DVT-X01,OSP,Blu,22L,21.122*3.470,G | GOLD CIRCUIT ELECTRONICS LTD. | 0101FGA00-000-G | G | PWA BOM | In New BOM |
|  |  |  | 0101FGA00-000-G | PCB,Zaius-Tri-mode BPX24 DVT-X01,OSP,Blu,22L,21.122*3.470,G | ZHUHAI FOUNDER PRINTED CIRCUIT BOARD（HK） DEVELOPMENT LIMITED | 0101FGA00-000-G | G | PWA BOM | In New BOM |
|  | PCB | 1 | 0101FGA00-000-G | PCB,Zaius-Tri-mode BPX24 DVT-X01,OSP,Blu,22L,21.122*3.470,G | NON DEDICATED | 0101FGA00-000-G | G | PWA BOM | In Old BOM |
| 2 | JSAS1,JPCIE1,JSAS2,JPCIE2,JSAS3,JPCIE3,JPCIE4,JPCIE5,JPCIE6,JPCIE7 | 10 | 340718A00-245-G | CONN,SAS,V/T,0.6mm,30u,G,SMD-74 | AMPHENOL SHANGHAI CORP. | U10-B074-250T | G | PWA BOM | In New BOM |
|  |  |  | U10-B274-250T | CONN,SAS,V/T,0.6mm,30u,G,SMD-74 | AMPHENOL SHANGHAI CORP. | U10-B274-250T | G | PWA BOM | In New BOM |
|  | JSAS1,JPCIE1,JSAS2,JPCIE2,JSAS3,JPCIE3,JPCIE4,JPCIE5,JPCIE6,JPCIE7 | 10 | 340718A00-245-G | CONN,SAS,V/T,0.6mm,30u,G,SMD-74 | AMPHENOL SHANGHAI CORP. | U10-B074-250T | G | PWA BOM | In Old BOM |
| ##### Change Revision |  |  |  |  |  |  |  |  |  |
| Sheet | REV OF BOM | CUSTOMER | CUSTOMER P/N | PWA PN | PWA DESCRIPTION | PWA REV | DATE | Remark |  |
| OOOOOOOOOOOOOOOOOOOOOOOOOOOOOOOOOOOOOOOOOOOOOOOOOOOOOOOOOOOOOOOOOOOOOOOOOOOOOOOOOOOOOOOOOO | OOOOOOOOOOOOOOOOOOOOOOOOOOOOOOOOOOOOOOOOOOOOOOOOOOOOOOOOOOOOOOOOOOOOOOOOOOOOOOOOOOOOOOOOOO | OOOOOOOOOOOOOOOOOOOOOOOOOOOOOOOOOOOOOOOOOOOOOOOOOOOOOOOOOOOOOOOOOOOOOOOOOOOOOOOOOOOOOOOOOO | OOOOOOOOOOOOOOOOOOOOOOOOOOOOOOOOOOOOOOOOOOOOOOOOOOOOOOOOOOOOOOOOOOOOOOOOOOOOOOOOOOOOOOOOOO | OOOOOOOOOOOOOOOOOOOOOOOOOOOOOOOOOOOOOOOOOOOOOOOOOOOOOOOOOOOOOOOOOOOOOOOOOOOOOOOOOOOOOOOOOO | OOOOOOOOOOOOOOOOOOOOOOOOOOOOOOOOOOOOOOOOOOOOOOOOOOOOOOOOOOOOOOOOOOOOOOOOOOOOOOOOOOOOOOOOOO | OOOOOOOOOOOOOOOOOOOOOOOOOOOOOOOOOOOOOOOOOOOOOOOOOOOOOOOOOOOOOOOOOOOOOOOOOOOOOOOOOOOOOOOOOO | OOOOOOOOOOOOOOOOOOOOOOOOOOOOOOOOOOOOOOOOOOOOOOOOOOOOOOOOOOOOOOOOOOOOOOOOOOOOOOOOOOOOOOOOOO | OOOOOOOOOOOOOOOOOOOOOOOOOOOOOOOOOOOOOOOOOOOOOOOOOOOOOOOOOOOOOOOOOOOOOOOOOOOOOOOOOOOOOOOOOO | OOOOOOOOOOOOOOOOOOOOOOOOOOOOOOOOOOOOOOOOOOOOOOOOOOOOOOOOOOOOOOOOOOOOOOOOOOOOOOOOOOOOOOOOOO |
| Second Source Change |  |  |  |  |  |  |  |  |  |
| Item | Location | Change Type | Foxconn P/N | Part Description | Manufacturer Full Name | Manufacturer P/N | RoHS | Sheet |  |
| 1 | JSAS1,JPCIE1,JSAS2,JPCIE2,JSAS3,JPCIE3,JPCIE4,JPCIE5,JPCIE6,JPCIE7 |  | 340718A00-245-G | CONN,SAS,V/T,0.6mm,30u,G,SMD-74 | AMPHENOL SHANGHAI CORP. | U10-B074-250T | G | PWA BOM |  |
|  |  | ADD | U10-B274-250T | CONN,SAS,V/T,0.6mm,30u,G,SMD-74 | AMPHENOL SHANGHAI CORP. | U10-B274-250T | G | PWA BOM |  |
| OOOOOOOOOOOOOOOOOOOOOOOOOOOOOOOOOOOOOOOOOOOOOOOOOOOOOOOOOOOOOOOOOOOOOOOOOOOOOOOOOOOOOOOOOO | OOOOOOOOOOOOOOOOOOOOOOOOOOOOOOOOOOOOOOOOOOOOOOOOOOOOOOOOOOOOOOOOOOOOOOOOOOOOOOOOOOOOOOOOOO | OOOOOOOOOOOOOOOOOOOOOOOOOOOOOOOOOOOOOOOOOOOOOOOOOOOOOOOOOOOOOOOOOOOOOOOOOOOOOOOOOOOOOOOOOO | OOOOOOOOOOOOOOOOOOOOOOOOOOOOOOOOOOOOOOOOOOOOOOOOOOOOOOOOOOOOOOOOOOOOOOOOOOOOOOOOOOOOOOOOOO | OOOOOOOOOOOOOOOOOOOOOOOOOOOOOOOOOOOOOOOOOOOOOOOOOOOOOOOOOOOOOOOOOOOOOOOOOOOOOOOOOOOOOOOOOO | OOOOOOOOOOOOOOOOOOOOOOOOOOOOOOOOOOOOOOOOOOOOOOOOOOOOOOOOOOOOOOOOOOOOOOOOOOOOOOOOOOOOOOOOOO | OOOOOOOOOOOOOOOOOOOOOOOOOOOOOOOOOOOOOOOOOOOOOOOOOOOOOOOOOOOOOOOOOOOOOOOOOOOOOOOOOOOOOOOOOO | OOOOOOOOOOOOOOOOOOOOOOOOOOOOOOOOOOOOOOOOOOOOOOOOOOOOOOOOOOOOOOOOOOOOOOOOOOOOOOOOOOOOOOOOOO | OOOOOOOOOOOOOOOOOOOOOOOOOOOOOOOOOOOOOOOOOOOOOOOOOOOOOOOOOOOOOOOOOOOOOOOOOOOOOOOOOOOOOOOOOO | OOOOOOOOOOOOOOOOOOOOOOOOOOOOOOOOOOOOOOOOOOOOOOOOOOOOOOOOOOOOOOOOOOOOOOOOOOOOOOOOOOOOOOOOOO |
| Master Materials Change |  |  |  |  |  |  |  |  |  |
| Item | Foxconn P/N | Orig._Usage | New_Usage | Part Description | Manufacturer Full Name | Manufacturer P/N | RoHS | Location | Sheet |
| 1 | 610107B00-017-G | 154 | 134 | RES,4.7KOhm,+/-5%,1/16W,G,SMD0402 | KOA SPEER ELECTRONICS, INC. | RK73B1ETTP472J | G | (-)R2160,R2161,R2162,R2163,R2164,R2165,R2166,R2167,R2168,R2169,R2170,R2171,R2172,R2173,R2174,R2175,R2176,R2177,R2178,R2179 | PWA BOM |
|  | 610107B00-012-G |  |  | RES,4.7KOhm,+/-5%,1/16W,G,SMD0402 | WALSIN TECHNOLOGY CORPORATION | WR04X472JTL |  |  | PWA BOM |
|  | 610107B00-011-G |  |  | RES,4.7KOhm,+/-5%,1/16W,G,SMD0402 | YAGEO CORPORATION COMPONENT | RC0402JR-074K7L |  |  | PWA BOM |
|  | 610107B00-044-G |  |  | RES,4.7KOhm,+/-5%,1/16W,G,SMD0402 | TA-I TECHNOLOGY CO., LTD | RM04JTN472 |  |  | PWA BOM |
|  | 610107B00-024-G |  |  | RES,4.7KOhm,+/-5%,1/16W,G,SMD0402 | PANASONIC INDUSTRIAL CO.,LTD. | ERJ2GEJ472X |  |  | PWA BOM |
|  | 610107B00-029-G |  |  | RES,4.7KOhm,+/-5%,1/16W,G,SMD0402 | VISHAY ENTER TECHNO LOGY.INC | CRCW04024K70JNED |  |  | PWA BOM |
| OOOOOOOOOOOOOOOOOOOOOOOOOOOOOOOOOOOOOOOOOOOOOOOOOOOOOOOOOOOOOOOOOOOOOOOOOOOOOOOOOOOOOOOOOO | OOOOOOOOOOOOOOOOOOOOOOOOOOOOOOOOOOOOOOOOOOOOOOOOOOOOOOOOOOOOOOOOOOOOOOOOOOOOOOOOOOOOOOOOOO | OOOOOOOOOOOOOOOOOOOOOOOOOOOOOOOOOOOOOOOOOOOOOOOOOOOOOOOOOOOOOOOOOOOOOOOOOOOOOOOOOOOOOOOOOO | OOOOOOOOOOOOOOOOOOOOOOOOOOOOOOOOOOOOOOOOOOOOOOOOOOOOOOOOOOOOOOOOOOOOOOOOOOOOOOOOOOOOOOOOOO | OOOOOOOOOOOOOOOOOOOOOOOOOOOOOOOOOOOOOOOOOOOOOOOOOOOOOOOOOOOOOOOOOOOOOOOOOOOOOOOOOOOOOOOOOO | OOOOOOOOOOOOOOOOOOOOOOOOOOOOOOOOOOOOOOOOOOOOOOOOOOOOOOOOOOOOOOOOOOOOOOOOOOOOOOOOOOOOOOOOOO | OOOOOOOOOOOOOOOOOOOOOOOOOOOOOOOOOOOOOOOOOOOOOOOOOOOOOOOOOOOOOOOOOOOOOOOOOOOOOOOOOOOOOOOOOO | OOOOOOOOOOOOOOOOOOOOOOOOOOOOOOOOOOOOOOOOOOOOOOOOOOOOOOOOOOOOOOOOOOOOOOOOOOOOOOOOOOOOOOOOOO | OOOOOOOOOOOOOOOOOOOOOOOOOOOOOOOOOOOOOOOOOOOOOOOOOOOOOOOOOOOOOOOOOOOOOOOOOOOOOOOOOOOOOOOOOO | OOOOOOOOOOOOOOOOOOOOOOOOOOOOOOOOOOOOOOOOOOOOOOOOOOOOOOOOOOOOOOOOOOOOOOOOOOOOOOOOOOOOOOOOOO |
| TLA Parts Change |  |  |  |  |  |  |  |  |  |
| Item | Foxconn P/N | Qty | Part Description | Manufacturer Full Name | Manufacturer P/N | RoHS | Location | Remark | BOM |
| BOM Change List Date:Fri Nov 03 14:53:20 GMT+08:00 2017 |  |  |  |  |  |  |  |  |  |
| New BOM file : E:\barreleye g2\1103\foxbis\BPX24 1103.xls |  |  |  |  |  |  |  |  |  |
| Old BOM file : E:\barreleye g2\1103\foxbis\BPX24 1024.xls |  |  |  |  |  |  |  |  |  |
| ##### Add Parts |  |  |  |  |  |  |  |  |  |
| Item | Location | Qty | Foxconn P/N | Part Description | Manufacturer Full Name | Manufacturer P/N | RoHS | Sheet |  |
| ##### Remove Parts |  |  |  |  |  |  |  |  |  |
| Item | Location | Qty | Foxconn P/N | Part Description | Manufacturer Full Name | Manufacturer P/N | RoHS | Sheet |  |
| ##### Change Parts |  |  |  |  |  |  |  |  |  |
| Item | Location | Qty | Foxconn P/N | Part Description | Manufacturer Full Name | Manufacturer P/N | RoHS | Sheet | Remark |
| 1 | L6,L28 | 2 | 72010FB01-016-G | FB,600 Ohm@100MHz,+/-25%,1A,150mOhm,G,SMD0603 | TDK ELECTRONICS EUROPE GMBH | MPZ1608S601AT | G | PWA BOM | In New BOM |
|  |  |  | 72010KF01-015-G | FB,600 Ohm@100MHz,+/-25%,1.3A,150mOhm,G,SMD0603 | MURATA ELEC. NORTH AMERICA | BLM18KG601SN1D | G | PWA BOM | In New BOM |
|  |  |  | 72010WP00-059-G | FB,600 Ohm@100MHz,+/-25%,1.5A,150mOhm,G,SMD0603 | TAI-TECH Advanced Electronics Co., Ltd. | HCB1608KF-601T15 | G | PWA BOM | In New BOM |
|  |  |  | 72010KF00-174-G | FB,600 Ohm@100MHz,+/-25%,1.3A,150mOhm,G,SMD0603 | MAX ECHO TECHNOLOGIES CORP | ACMS160808A601 1.3A | G | PWA BOM | In New BOM |
|  | L6,L28 | 2 | 72010FB01-016-G | FB,600 Ohm@100MHz,+/-25%,1A,150mOhm,G,SMD0603 | TDK ELECTRONICS EUROPE GMBH | MPZ1608S601AT | G | PWA BOM | In Old BOM |
| 2 | L30 | 1 | 720102001-015-G | FB,30 Ohm@100MHz,+/-25%,3A,15mOhm,G,SMD0805 | MURATA ELEC. NORTH AMERICA | BLM21PG300SN1D | G | PWA BOM | In New BOM |
|  |  |  | 720102002-129-G | FB,30 Ohm@100MHz,+/-25%,3A,15mOhm,G,SMD0805 | MAG.LAYERS, SCIENTIFIC-TECHNICS (KUNSHAN) CO., LTD. | GMLB-201209-0030P-N8-RM | G | PWA BOM | In New BOM |
|  | L30 | 1 | 720102001-015-G | FB,30 Ohm@100MHz,+/-25%,3A,15mOhm,G,SMD0805 | MURATA ELEC. NORTH AMERICA | BLM21PG300SN1D | G | PWA BOM | In Old BOM |
| 3 | L31 | 1 | 720101L00-015-G | FB,600 Ohm@100MHz,+/-25%,200mA,500mOhm,G,SMD0603 | MURATA ELEC. NORTH AMERICA | BLM18AG601SN1D | G | PWA BOM | In New BOM |
|  |  |  | 720101L00-026-G | FB,600 Ohm@100MHz,+/-25%,200mA,500mOhm,G,SMD0603 | SAMSUNG SEMICONDUCTOR | CIM10U601NC | G | PWA BOM | In New BOM |
|  |  |  | 720101L00-074-G | FB,600Ohm@100MHz,+/-25%,200mA,500mOhm,SMD0603,G | CHILISIN ELECTRONICS CORP. | SBK160808T-601Y-N | G | PWA BOM | In New BOM |
|  |  |  | 720105E04-016-G | FB,600Ohm@100MHz,+/-25%,500mA,400mOhm,SMD0603,G | TDK ELECTRONICS EUROPE GMBH | MMZ1608B601CTAH0 | G | PWA BOM | In New BOM |
|  | L31 | 1 | 720101L00-015-G | FB,600 Ohm@100MHz,+/-25%,200mA,500mOhm,G,SMD0603 | MURATA ELEC. NORTH AMERICA | BLM18AG601SN1D | G | PWA BOM | In Old BOM |
| 4 | PSRR19 | 1 | 61100YB00-017-G | RES,2.94KOhm,+/-0.1%,1/16W,G,SMD0402 | KOA SPEER ELECTRONICS, INC. | RN731ETTP2941B25 | G | PWA BOM | In New BOM |
|  |  |  | 61100YB00-011-G | RES,2.94KOhm,+/-0.1%,1/16W,G,SMD0402 | YAGEO CORPORATION COMPONENT | RT0402BRD072K94L | G | PWA BOM | In New BOM |
|  |  |  | 61100YB00-044-G | RES,2.94KOhm,+/-0.1%,1/16W,G,SMD0402 | TA-I TECHNOLOGY CO., LTD | RB04BTP2941 | G | PWA BOM | In New BOM |
|  | PSRR19 | 1 | 61100YB00-017-G | RES,2.94KOhm,+/-0.1%,1/16W,G,SMD0402 | KOA SPEER ELECTRONICS, INC. | RN731ETTP2941B25 | G | PWA BOM | In Old BOM |
| 5 | J_NVME01,J_NVME02,J_NVME03,J_NVME04,J_NVME05,J_NVME06,J_NVME07,J_NVME08,J_NVME09,J_NVME10,J_NVME11,J_NVME12,J_NVME13,J_NVME14,J_NVME15,J_NVME16,J_NVME17,J_NVME18,J_NVME19,J_NVME20,J_NVME21,J_NVME22,J_NVME23,J_NVME00 | 24 | 340313H00-600-G | CONN,PCIE,V/T,Bla,0.8mm,30u,G,SMD-68 | FOXCONN TECHNOLOGY CO.,LTD. | LU25683-A001-9H | G | PWA BOM | In New BOM |
|  |  |  | 34031BQ00-317-G | CONN,PCIE,V/T,Bla,0.8mm,30u,G,SMD-68 | MOLEX INCORPORATED | 78777-1002 | G | PWA BOM | In New BOM |
|  | J_NVME01,J_NVME02,J_NVME03,J_NVME04,J_NVME05,J_NVME06,J_NVME07,J_NVME08,J_NVME09,J_NVME10,J_NVME11,J_NVME12,J_NVME13,J_NVME14,J_NVME15,J_NVME16,J_NVME17,J_NVME18,J_NVME19,J_NVME20,J_NVME21,J_NVME22,J_NVME23,J_NVME00 | 24 | 340313H00-600-G | CONN,PCIE,V/T,Bla,0.8mm,30u,G,SMD-68 | FOXCONN TECHNOLOGY CO.,LTD. | LU25683-A001-9H | G | PWA BOM | In Old BOM |
| ##### Change Revision |  |  |  |  |  |  |  |  |  |
| Sheet | REV OF BOM | CUSTOMER | CUSTOMER P/N | PWA PN | PWA DESCRIPTION | PWA REV | DATE | Remark |  |
| OOOOOOOOOOOOOOOOOOOOOOOOOOOOOOOOOOOOOOOOOOOOOOOOOOOOOOOOOOOOOOOOOOOOOOOOOOOOOOOOOOOOOOOOOO | OOOOOOOOOOOOOOOOOOOOOOOOOOOOOOOOOOOOOOOOOOOOOOOOOOOOOOOOOOOOOOOOOOOOOOOOOOOOOOOOOOOOOOOOOO | OOOOOOOOOOOOOOOOOOOOOOOOOOOOOOOOOOOOOOOOOOOOOOOOOOOOOOOOOOOOOOOOOOOOOOOOOOOOOOOOOOOOOOOOOO | OOOOOOOOOOOOOOOOOOOOOOOOOOOOOOOOOOOOOOOOOOOOOOOOOOOOOOOOOOOOOOOOOOOOOOOOOOOOOOOOOOOOOOOOOO | OOOOOOOOOOOOOOOOOOOOOOOOOOOOOOOOOOOOOOOOOOOOOOOOOOOOOOOOOOOOOOOOOOOOOOOOOOOOOOOOOOOOOOOOOO | OOOOOOOOOOOOOOOOOOOOOOOOOOOOOOOOOOOOOOOOOOOOOOOOOOOOOOOOOOOOOOOOOOOOOOOOOOOOOOOOOOOOOOOOOO | OOOOOOOOOOOOOOOOOOOOOOOOOOOOOOOOOOOOOOOOOOOOOOOOOOOOOOOOOOOOOOOOOOOOOOOOOOOOOOOOOOOOOOOOOO | OOOOOOOOOOOOOOOOOOOOOOOOOOOOOOOOOOOOOOOOOOOOOOOOOOOOOOOOOOOOOOOOOOOOOOOOOOOOOOOOOOOOOOOOOO | OOOOOOOOOOOOOOOOOOOOOOOOOOOOOOOOOOOOOOOOOOOOOOOOOOOOOOOOOOOOOOOOOOOOOOOOOOOOOOOOOOOOOOOOOO | OOOOOOOOOOOOOOOOOOOOOOOOOOOOOOOOOOOOOOOOOOOOOOOOOOOOOOOOOOOOOOOOOOOOOOOOOOOOOOOOOOOOOOOOOO |
| Second Source Change |  |  |  |  |  |  |  |  |  |
| Item | Location | Change Type | Foxconn P/N | Part Description | Manufacturer Full Name | Manufacturer P/N | RoHS | Sheet |  |
| 1 | L6,L28 |  | 72010FB01-016-G | FB,600 Ohm@100MHz,+/-25%,1A,150mOhm,G,SMD0603 | TDK ELECTRONICS EUROPE GMBH | MPZ1608S601AT | G | PWA BOM |  |
|  |  | ADD | 72010KF01-015-G | FB,600 Ohm@100MHz,+/-25%,1.3A,150mOhm,G,SMD0603 | MURATA ELEC. NORTH AMERICA | BLM18KG601SN1D | G | PWA BOM |  |
|  |  | ADD | 72010WP00-059-G | FB,600 Ohm@100MHz,+/-25%,1.5A,150mOhm,G,SMD0603 | TAI-TECH Advanced Electronics Co., Ltd. | HCB1608KF-601T15 | G | PWA BOM |  |
|  |  | ADD | 72010KF00-174-G | FB,600 Ohm@100MHz,+/-25%,1.3A,150mOhm,G,SMD0603 | MAX ECHO TECHNOLOGIES CORP | ACMS160808A601 1.3A | G | PWA BOM |  |
| 2 | L30 |  | 720102001-015-G | FB,30 Ohm@100MHz,+/-25%,3A,15mOhm,G,SMD0805 | MURATA ELEC. NORTH AMERICA | BLM21PG300SN1D | G | PWA BOM |  |
|  |  | ADD | 720102002-129-G | FB,30 Ohm@100MHz,+/-25%,3A,15mOhm,G,SMD0805 | MAG.LAYERS, SCIENTIFIC-TECHNICS (KUNSHAN) CO., LTD. | GMLB-201209-0030P-N8-RM | G | PWA BOM |  |
| 3 | L31 |  | 720101L00-015-G | FB,600 Ohm@100MHz,+/-25%,200mA,500mOhm,G,SMD0603 | MURATA ELEC. NORTH AMERICA | BLM18AG601SN1D | G | PWA BOM |  |
|  |  | ADD | 720101L00-026-G | FB,600 Ohm@100MHz,+/-25%,200mA,500mOhm,G,SMD0603 | SAMSUNG SEMICONDUCTOR | CIM10U601NC | G | PWA BOM |  |
|  |  | ADD | 720101L00-074-G | FB,600Ohm@100MHz,+/-25%,200mA,500mOhm,SMD0603,G | CHILISIN ELECTRONICS CORP. | SBK160808T-601Y-N | G | PWA BOM |  |
|  |  | ADD | 720105E04-016-G | FB,600Ohm@100MHz,+/-25%,500mA,400mOhm,SMD0603,G | TDK ELECTRONICS EUROPE GMBH | MMZ1608B601CTAH0 | G | PWA BOM |  |
| 4 | PSRR19 |  | 61100YB00-017-G | RES,2.94KOhm,+/-0.1%,1/16W,G,SMD0402 | KOA SPEER ELECTRONICS, INC. | RN731ETTP2941B25 | G | PWA BOM |  |
|  |  | ADD | 61100YB00-011-G | RES,2.94KOhm,+/-0.1%,1/16W,G,SMD0402 | YAGEO CORPORATION COMPONENT | RT0402BRD072K94L | G | PWA BOM |  |
|  |  | ADD | 61100YB00-044-G | RES,2.94KOhm,+/-0.1%,1/16W,G,SMD0402 | TA-I TECHNOLOGY CO., LTD | RB04BTP2941 | G | PWA BOM |  |
| 5 | J_NVME01,J_NVME02,J_NVME03,J_NVME04,J_NVME05,J_NVME06,J_NVME07,J_NVME08,J_NVME09,J_NVME10,J_NVME11,J_NVME12,J_NVME13,J_NVME14,J_NVME15,J_NVME16,J_NVME17,J_NVME18,J_NVME19,J_NVME20,J_NVME21,J_NVME22,J_NVME23,J_NVME00 |  | 340313H00-600-G | CONN,PCIE,V/T,Bla,0.8mm,30u,G,SMD-68 | FOXCONN TECHNOLOGY CO.,LTD. | LU25683-A001-9H | G | PWA BOM |  |
|  |  | ADD | 34031BQ00-317-G | CONN,PCIE,V/T,Bla,0.8mm,30u,G,SMD-68 | MOLEX INCORPORATED | 78777-1002 | G | PWA BOM |  |
| OOOOOOOOOOOOOOOOOOOOOOOOOOOOOOOOOOOOOOOOOOOOOOOOOOOOOOOOOOOOOOOOOOOOOOOOOOOOOOOOOOOOOOOOOO | OOOOOOOOOOOOOOOOOOOOOOOOOOOOOOOOOOOOOOOOOOOOOOOOOOOOOOOOOOOOOOOOOOOOOOOOOOOOOOOOOOOOOOOOOO | OOOOOOOOOOOOOOOOOOOOOOOOOOOOOOOOOOOOOOOOOOOOOOOOOOOOOOOOOOOOOOOOOOOOOOOOOOOOOOOOOOOOOOOOOO | OOOOOOOOOOOOOOOOOOOOOOOOOOOOOOOOOOOOOOOOOOOOOOOOOOOOOOOOOOOOOOOOOOOOOOOOOOOOOOOOOOOOOOOOOO | OOOOOOOOOOOOOOOOOOOOOOOOOOOOOOOOOOOOOOOOOOOOOOOOOOOOOOOOOOOOOOOOOOOOOOOOOOOOOOOOOOOOOOOOOO | OOOOOOOOOOOOOOOOOOOOOOOOOOOOOOOOOOOOOOOOOOOOOOOOOOOOOOOOOOOOOOOOOOOOOOOOOOOOOOOOOOOOOOOOOO | OOOOOOOOOOOOOOOOOOOOOOOOOOOOOOOOOOOOOOOOOOOOOOOOOOOOOOOOOOOOOOOOOOOOOOOOOOOOOOOOOOOOOOOOOO | OOOOOOOOOOOOOOOOOOOOOOOOOOOOOOOOOOOOOOOOOOOOOOOOOOOOOOOOOOOOOOOOOOOOOOOOOOOOOOOOOOOOOOOOOO | OOOOOOOOOOOOOOOOOOOOOOOOOOOOOOOOOOOOOOOOOOOOOOOOOOOOOOOOOOOOOOOOOOOOOOOOOOOOOOOOOOOOOOOOOO | OOOOOOOOOOOOOOOOOOOOOOOOOOOOOOOOOOOOOOOOOOOOOOOOOOOOOOOOOOOOOOOOOOOOOOOOOOOOOOOOOOOOOOOOOO |
| Master Materials Change |  |  |  |  |  |  |  |  |  |
| Item | Foxconn P/N | Orig._Usage | New_Usage | Part Description | Manufacturer Full Name | Manufacturer P/N | RoHS | Location | Sheet |
| OOOOOOOOOOOOOOOOOOOOOOOOOOOOOOOOOOOOOOOOOOOOOOOOOOOOOOOOOOOOOOOOOOOOOOOOOOOOOOOOOOOOOOOOOO | OOOOOOOOOOOOOOOOOOOOOOOOOOOOOOOOOOOOOOOOOOOOOOOOOOOOOOOOOOOOOOOOOOOOOOOOOOOOOOOOOOOOOOOOOO | OOOOOOOOOOOOOOOOOOOOOOOOOOOOOOOOOOOOOOOOOOOOOOOOOOOOOOOOOOOOOOOOOOOOOOOOOOOOOOOOOOOOOOOOOO | OOOOOOOOOOOOOOOOOOOOOOOOOOOOOOOOOOOOOOOOOOOOOOOOOOOOOOOOOOOOOOOOOOOOOOOOOOOOOOOOOOOOOOOOOO | OOOOOOOOOOOOOOOOOOOOOOOOOOOOOOOOOOOOOOOOOOOOOOOOOOOOOOOOOOOOOOOOOOOOOOOOOOOOOOOOOOOOOOOOOO | OOOOOOOOOOOOOOOOOOOOOOOOOOOOOOOOOOOOOOOOOOOOOOOOOOOOOOOOOOOOOOOOOOOOOOOOOOOOOOOOOOOOOOOOOO | OOOOOOOOOOOOOOOOOOOOOOOOOOOOOOOOOOOOOOOOOOOOOOOOOOOOOOOOOOOOOOOOOOOOOOOOOOOOOOOOOOOOOOOOOO | OOOOOOOOOOOOOOOOOOOOOOOOOOOOOOOOOOOOOOOOOOOOOOOOOOOOOOOOOOOOOOOOOOOOOOOOOOOOOOOOOOOOOOOOOO | OOOOOOOOOOOOOOOOOOOOOOOOOOOOOOOOOOOOOOOOOOOOOOOOOOOOOOOOOOOOOOOOOOOOOOOOOOOOOOOOOOOOOOOOOO | OOOOOOOOOOOOOOOOOOOOOOOOOOOOOOOOOOOOOOOOOOOOOOOOOOOOOOOOOOOOOOOOOOOOOOOOOOOOOOOOOOOOOOOOOO |
| TLA Parts Change |  |  |  |  |  |  |  |  |  |
| Item | Foxconn P/N | Qty | Part Description | Manufacturer Full Name | Manufacturer P/N | RoHS | Location | Remark | BOM |
| BOM Change List Date:Fri Dec 08 14:23:37 GMT+08:00 2017 |  |  |  |  |  |  |  |  |  |
| New BOM file : E:\barreleye g2\1208\BPX24 1208.xls |  |  |  |  |  |  |  |  |  |
| Old BOM file : E:\barreleye g2\1208\BPX24 1110.xls |  |  |  |  |  |  |  |  |  |
| ##### Add Parts |  |  |  |  |  |  |  |  |  |
| Item | Location | Qty | Foxconn P/N | Part Description | Manufacturer Full Name | Manufacturer P/N | RoHS | Sheet |  |
| ##### Remove Parts |  |  |  |  |  |  |  |  |  |
| Item | Location | Qty | Foxconn P/N | Part Description | Manufacturer Full Name | Manufacturer P/N | RoHS | Sheet |  |
| ##### Change Parts |  |  |  |  |  |  |  |  |  |
| Item | Location | Qty | Foxconn P/N | Part Description | Manufacturer Full Name | Manufacturer P/N | RoHS | Sheet | Remark |
| 1 | L1 | 1 | 720101900-015-G | FB,60 Ohm@100MHz,+/-25%,3A,25mOhm,G,SMD0805 | MURATA ELEC. NORTH AMERICA | BLM21PG600SN1D | G | PWA BOM | In New BOM |
|  |  |  | 720101900-026-G | FB,60 Ohm@100MHz,+/-25%,3A,25mOhm,G,SMD0805 | SAMSUNG SEMICONDUCTOR | CIC21P600NE | G | PWA BOM | In New BOM |
|  |  |  | 720104100-074-G | FB,60 Ohm@100MHz,+/-25%,3A,30mOhm,G,SMD0805 | CHILISIN ELECTRONICS CORP. | PBY201209T-600Y-N | G | PWA BOM | In New BOM |
|  | L1 | 1 | 720101900-015-G | FB,60 Ohm@100MHz,+/-25%,3A,25mOhm,G,SMD0805 | MURATA ELEC. NORTH AMERICA | BLM21PG600SN1D | G | PWA BOM | In Old BOM |
|  |  |  | 720101900-026-G | FB,60 Ohm@100MHz,+/-25%,3A,25mOhm,G,SMD0805 | SAMSUNG SEMICONDUCTOR | CIC21P600NE | G | PWA BOM | In Old BOM |
| 2 | L31 | 1 | 720101L00-015-G | FB,600 Ohm@100MHz,+/-25%,200mA,500mOhm,G,SMD0603 | MURATA ELEC. NORTH AMERICA | BLM18AG601SN1D | G | PWA BOM | In New BOM |
|  |  |  | 720101L00-074-G | FB,600Ohm@100MHz,+/-25%,200mA,500mOhm,SMD0603,G | CHILISIN ELECTRONICS CORP. | SBK160808T-601Y-N | G | PWA BOM | In New BOM |
|  |  |  | 720105E04-016-G | FB,600Ohm@100MHz,+/-25%,500mA,400mOhm,SMD0603,G | TDK ELECTRONICS EUROPE GMBH | MMZ1608B601CTAH0 | G | PWA BOM | In New BOM |
|  | L31 | 1 | 720101L00-015-G | FB,600 Ohm@100MHz,+/-25%,200mA,500mOhm,G,SMD0603 | MURATA ELEC. NORTH AMERICA | BLM18AG601SN1D | G | PWA BOM | In Old BOM |
|  |  |  | 720101L00-026-G | FB,600 Ohm@100MHz,+/-25%,200mA,500mOhm,G,SMD0603 | SAMSUNG SEMICONDUCTOR | CIM10U601NC | G | PWA BOM | In Old BOM |
|  |  |  | 720101L00-074-G | FB,600Ohm@100MHz,+/-25%,200mA,500mOhm,SMD0603,G | CHILISIN ELECTRONICS CORP. | SBK160808T-601Y-N | G | PWA BOM | In Old BOM |
|  |  |  | 720105E04-016-G | FB,600Ohm@100MHz,+/-25%,500mA,400mOhm,SMD0603,G | TDK ELECTRONICS EUROPE GMBH | MMZ1608B601CTAH0 | G | PWA BOM | In Old BOM |
| ##### Change Revision |  |  |  |  |  |  |  |  |  |
| Sheet | REV OF BOM | CUSTOMER | CUSTOMER P/N | PWA PN | PWA DESCRIPTION | PWA REV | DATE | Remark |  |
| OOOOOOOOOOOOOOOOOOOOOOOOOOOOOOOOOOOOOOOOOOOOOOOOOOOOOOOOOOOOOOOOOOOOOOOOOOOOOOOOOOOOOOOOOO | OOOOOOOOOOOOOOOOOOOOOOOOOOOOOOOOOOOOOOOOOOOOOOOOOOOOOOOOOOOOOOOOOOOOOOOOOOOOOOOOOOOOOOOOOO | OOOOOOOOOOOOOOOOOOOOOOOOOOOOOOOOOOOOOOOOOOOOOOOOOOOOOOOOOOOOOOOOOOOOOOOOOOOOOOOOOOOOOOOOOO | OOOOOOOOOOOOOOOOOOOOOOOOOOOOOOOOOOOOOOOOOOOOOOOOOOOOOOOOOOOOOOOOOOOOOOOOOOOOOOOOOOOOOOOOOO | OOOOOOOOOOOOOOOOOOOOOOOOOOOOOOOOOOOOOOOOOOOOOOOOOOOOOOOOOOOOOOOOOOOOOOOOOOOOOOOOOOOOOOOOOO | OOOOOOOOOOOOOOOOOOOOOOOOOOOOOOOOOOOOOOOOOOOOOOOOOOOOOOOOOOOOOOOOOOOOOOOOOOOOOOOOOOOOOOOOOO | OOOOOOOOOOOOOOOOOOOOOOOOOOOOOOOOOOOOOOOOOOOOOOOOOOOOOOOOOOOOOOOOOOOOOOOOOOOOOOOOOOOOOOOOOO | OOOOOOOOOOOOOOOOOOOOOOOOOOOOOOOOOOOOOOOOOOOOOOOOOOOOOOOOOOOOOOOOOOOOOOOOOOOOOOOOOOOOOOOOOO | OOOOOOOOOOOOOOOOOOOOOOOOOOOOOOOOOOOOOOOOOOOOOOOOOOOOOOOOOOOOOOOOOOOOOOOOOOOOOOOOOOOOOOOOOO | OOOOOOOOOOOOOOOOOOOOOOOOOOOOOOOOOOOOOOOOOOOOOOOOOOOOOOOOOOOOOOOOOOOOOOOOOOOOOOOOOOOOOOOOOO |
| Second Source Change |  |  |  |  |  |  |  |  |  |
| Item | Location | Change Type | Foxconn P/N | Part Description | Manufacturer Full Name | Manufacturer P/N | RoHS | Sheet |  |
| 1 | L1 |  | 720101900-015-G | FB,60 Ohm@100MHz,+/-25%,3A,25mOhm,G,SMD0805 | MURATA ELEC. NORTH AMERICA | BLM21PG600SN1D | G | PWA BOM |  |
|  |  | NO | 720101900-026-G | FB,60 Ohm@100MHz,+/-25%,3A,25mOhm,G,SMD0805 | SAMSUNG SEMICONDUCTOR | CIC21P600NE | G | PWA BOM |  |
|  |  | ADD | 720104100-074-G | FB,60 Ohm@100MHz,+/-25%,3A,30mOhm,G,SMD0805 | CHILISIN ELECTRONICS CORP. | PBY201209T-600Y-N | G | PWA BOM |  |
| 2 | L31 |  | 720101L00-015-G | FB,600 Ohm@100MHz,+/-25%,200mA,500mOhm,G,SMD0603 | MURATA ELEC. NORTH AMERICA | BLM18AG601SN1D | G | PWA BOM |  |
|  |  | NO | 720101L00-074-G | FB,600Ohm@100MHz,+/-25%,200mA,500mOhm,SMD0603,G | CHILISIN ELECTRONICS CORP. | SBK160808T-601Y-N | G | PWA BOM |  |
|  |  | NO | 720105E04-016-G | FB,600Ohm@100MHz,+/-25%,500mA,400mOhm,SMD0603,G | TDK ELECTRONICS EUROPE GMBH | MMZ1608B601CTAH0 | G | PWA BOM |  |
|  |  | Delete | 720101L00-026-G | FB,600 Ohm@100MHz,+/-25%,200mA,500mOhm,G,SMD0603 | SAMSUNG SEMICONDUCTOR | CIM10U601NC | G | PWA BOM |  |
| OOOOOOOOOOOOOOOOOOOOOOOOOOOOOOOOOOOOOOOOOOOOOOOOOOOOOOOOOOOOOOOOOOOOOOOOOOOOOOOOOOOOOOOOOO | OOOOOOOOOOOOOOOOOOOOOOOOOOOOOOOOOOOOOOOOOOOOOOOOOOOOOOOOOOOOOOOOOOOOOOOOOOOOOOOOOOOOOOOOOO | OOOOOOOOOOOOOOOOOOOOOOOOOOOOOOOOOOOOOOOOOOOOOOOOOOOOOOOOOOOOOOOOOOOOOOOOOOOOOOOOOOOOOOOOOO | OOOOOOOOOOOOOOOOOOOOOOOOOOOOOOOOOOOOOOOOOOOOOOOOOOOOOOOOOOOOOOOOOOOOOOOOOOOOOOOOOOOOOOOOOO | OOOOOOOOOOOOOOOOOOOOOOOOOOOOOOOOOOOOOOOOOOOOOOOOOOOOOOOOOOOOOOOOOOOOOOOOOOOOOOOOOOOOOOOOOO | OOOOOOOOOOOOOOOOOOOOOOOOOOOOOOOOOOOOOOOOOOOOOOOOOOOOOOOOOOOOOOOOOOOOOOOOOOOOOOOOOOOOOOOOOO | OOOOOOOOOOOOOOOOOOOOOOOOOOOOOOOOOOOOOOOOOOOOOOOOOOOOOOOOOOOOOOOOOOOOOOOOOOOOOOOOOOOOOOOOOO | OOOOOOOOOOOOOOOOOOOOOOOOOOOOOOOOOOOOOOOOOOOOOOOOOOOOOOOOOOOOOOOOOOOOOOOOOOOOOOOOOOOOOOOOOO | OOOOOOOOOOOOOOOOOOOOOOOOOOOOOOOOOOOOOOOOOOOOOOOOOOOOOOOOOOOOOOOOOOOOOOOOOOOOOOOOOOOOOOOOOO | OOOOOOOOOOOOOOOOOOOOOOOOOOOOOOOOOOOOOOOOOOOOOOOOOOOOOOOOOOOOOOOOOOOOOOOOOOOOOOOOOOOOOOOOOO |
| Master Materials Change |  |  |  |  |  |  |  |  |  |
| Item | Foxconn P/N | Orig._Usage | New_Usage | Part Description | Manufacturer Full Name | Manufacturer P/N | RoHS | Location | Sheet |
| OOOOOOOOOOOOOOOOOOOOOOOOOOOOOOOOOOOOOOOOOOOOOOOOOOOOOOOOOOOOOOOOOOOOOOOOOOOOOOOOOOOOOOOOOO | OOOOOOOOOOOOOOOOOOOOOOOOOOOOOOOOOOOOOOOOOOOOOOOOOOOOOOOOOOOOOOOOOOOOOOOOOOOOOOOOOOOOOOOOOO | OOOOOOOOOOOOOOOOOOOOOOOOOOOOOOOOOOOOOOOOOOOOOOOOOOOOOOOOOOOOOOOOOOOOOOOOOOOOOOOOOOOOOOOOOO | OOOOOOOOOOOOOOOOOOOOOOOOOOOOOOOOOOOOOOOOOOOOOOOOOOOOOOOOOOOOOOOOOOOOOOOOOOOOOOOOOOOOOOOOOO | OOOOOOOOOOOOOOOOOOOOOOOOOOOOOOOOOOOOOOOOOOOOOOOOOOOOOOOOOOOOOOOOOOOOOOOOOOOOOOOOOOOOOOOOOO | OOOOOOOOOOOOOOOOOOOOOOOOOOOOOOOOOOOOOOOOOOOOOOOOOOOOOOOOOOOOOOOOOOOOOOOOOOOOOOOOOOOOOOOOOO | OOOOOOOOOOOOOOOOOOOOOOOOOOOOOOOOOOOOOOOOOOOOOOOOOOOOOOOOOOOOOOOOOOOOOOOOOOOOOOOOOOOOOOOOOO | OOOOOOOOOOOOOOOOOOOOOOOOOOOOOOOOOOOOOOOOOOOOOOOOOOOOOOOOOOOOOOOOOOOOOOOOOOOOOOOOOOOOOOOOOO | OOOOOOOOOOOOOOOOOOOOOOOOOOOOOOOOOOOOOOOOOOOOOOOOOOOOOOOOOOOOOOOOOOOOOOOOOOOOOOOOOOOOOOOOOO | OOOOOOOOOOOOOOOOOOOOOOOOOOOOOOOOOOOOOOOOOOOOOOOOOOOOOOOOOOOOOOOOOOOOOOOOOOOOOOOOOOOOOOOOOO |
| TLA Parts Change |  |  |  |  |  |  |  |  |  |
| Item | Foxconn P/N | Qty | Part Description | Manufacturer Full Name | Manufacturer P/N | RoHS | Location | Remark | BOM |
